G04 CAM350 V10.2.1 (Build 391) Date:  Fri Dec 30 15:05:17 2016 *
G04 Database: (Untitled) *
G04 Layer 8: TSMD.art *
%FSLAX35Y35*%
%MOIN*%
%SFA1.000B1.000*%

%MIA0B0*%
%IPPOS*%
%AMMACRO46*
4,1,40,0.01300,0.01700,-0.01300,0.01700,-0.01369,0.01694,-0.01437,0.01676,-0.01500,0.01646,-0.01557,0.01606,-0.01606,0.01557,-0.01646,0.01500,-0.01676,0.01437,-0.01694,0.01370,-0.01700,0.01300,-0.01700,-0.01300,-0.01694,-0.01369,-0.01676,-0.01437,-0.01646,-0.01500,-0.01606,-0.01557,-0.01557,-0.01606,-0.01500,-0.01646,-0.01437,-0.01676,-0.01369,-0.01694,-0.01300,-0.01700,0.01300,-0.01700,0.01370,-0.01694,0.01437,-0.01676,0.01500,-0.01646,0.01557,-0.01606,0.01606,-0.01557,0.01646,-0.01500,0.01676,-0.01437,0.01694,-0.01369,0.01700,-0.01300,0.01700,0.01300,0.01694,0.01370,0.01676,0.01437,0.01646,0.01500,0.01606,0.01557,0.01557,0.01606,0.01500,0.01646,0.01437,0.01676,0.01370,0.01694,0.01300,0.01700,0.00000*
%
%AMMACRO24_1*
4,1,40,0.01700,-0.01300,0.01700,0.01300,0.01694,0.01370,0.01676,0.01437,0.01646,0.01500,0.01606,0.01557,0.01557,0.01606,0.01500,0.01646,0.01437,0.01676,0.01370,0.01694,0.01300,0.01700,-0.01300,0.01700,-0.01369,0.01694,-0.01437,0.01676,-0.01500,0.01646,-0.01557,0.01606,-0.01606,0.01557,-0.01646,0.01500,-0.01676,0.01437,-0.01694,0.01370,-0.01700,0.01300,-0.01700,-0.01300,-0.01694,-0.01369,-0.01676,-0.01437,-0.01646,-0.01500,-0.01606,-0.01557,-0.01557,-0.01606,-0.01500,-0.01646,-0.01437,-0.01676,-0.01369,-0.01694,-0.01300,-0.01700,0.01300,-0.01700,0.01370,-0.01694,0.01437,-0.01676,0.01500,-0.01646,0.01557,-0.01606,0.01606,-0.01557,0.01646,-0.01500,0.01676,-0.01437,0.01694,-0.01369,0.01700,-0.01300,0.00000*
%
%AMMACRO40*
4,1,40,0.01100,-0.00700,0.01100,0.00700,0.01094,0.00770,0.01076,0.00837,0.01046,0.00900,0.01006,0.00957,0.00957,0.01006,0.00900,0.01046,0.00837,0.01076,0.00770,0.01094,0.00700,0.01100,-0.00700,0.01100,-0.00769,0.01094,-0.00837,0.01076,-0.00900,0.01046,-0.00957,0.01006,-0.01006,0.00957,-0.01046,0.00900,-0.01076,0.00837,-0.01094,0.00770,-0.01100,0.00700,-0.01100,-0.00700,-0.01094,-0.00769,-0.01076,-0.00837,-0.01046,-0.00900,-0.01006,-0.00957,-0.00957,-0.01006,-0.00900,-0.01046,-0.00837,-0.01076,-0.00769,-0.01094,-0.00700,-0.01100,0.00700,-0.01100,0.00770,-0.01094,0.00837,-0.01076,0.00900,-0.01046,0.00957,-0.01006,0.01006,-0.00957,0.01046,-0.00900,0.01076,-0.00837,0.01094,-0.00769,0.01100,-0.00700,0.00000*
%
%AMMACRO16_1*
4,1,40,0.00700,0.01100,-0.00700,0.01100,-0.00769,0.01094,-0.00837,0.01076,-0.00900,0.01046,-0.00957,0.01006,-0.01006,0.00957,-0.01046,0.00900,-0.01076,0.00837,-0.01094,0.00770,-0.01100,0.00700,-0.01100,-0.00700,-0.01094,-0.00769,-0.01076,-0.00837,-0.01046,-0.00900,-0.01006,-0.00957,-0.00957,-0.01006,-0.00900,-0.01046,-0.00837,-0.01076,-0.00769,-0.01094,-0.00700,-0.01100,0.00700,-0.01100,0.00770,-0.01094,0.00837,-0.01076,0.00900,-0.01046,0.00957,-0.01006,0.01006,-0.00957,0.01046,-0.00900,0.01076,-0.00837,0.01094,-0.00769,0.01100,-0.00700,0.01100,0.00700,0.01094,0.00770,0.01076,0.00837,0.01046,0.00900,0.01006,0.00957,0.00957,0.01006,0.00900,0.01046,0.00837,0.01076,0.00770,0.01094,0.00700,0.01100,0.00000*
%
%AMMACRO22_1*
4,1,20,-0.04700,-0.03200,-0.04700,-0.01550,-0.07400,-0.01550,-0.07400,-0.00450,-0.04900,-0.00450,-0.04900,0.00450,-0.07400,0.00450,-0.07400,0.01550,-0.04700,0.01550,-0.04700,0.03200,0.04700,0.03200,0.04700,0.01550,0.07400,0.01550,0.07400,0.00450,0.04900,0.00450,0.04900,-0.00450,0.07400,-0.00450,0.07400,-0.01550,0.04700,-0.01550,0.04700,-0.03200,-0.04700,-0.03200,0.00000*
%
%AMMACRO32*
4,1,40,-0.01200,0.00800,-0.01200,-0.00800,-0.01194,-0.00869,-0.01176,-0.00937,-0.01146,-0.01000,-0.01106,-0.01057,-0.01057,-0.01106,-0.01000,-0.01146,-0.00937,-0.01176,-0.00869,-0.01194,-0.00800,-0.01200,0.00800,-0.01200,0.00870,-0.01194,0.00937,-0.01176,0.01000,-0.01146,0.01057,-0.01106,0.01106,-0.01057,0.01146,-0.01000,0.01176,-0.00937,0.01194,-0.00869,0.01200,-0.00800,0.01200,0.00800,0.01194,0.00870,0.01176,0.00937,0.01146,0.01000,0.01106,0.01057,0.01057,0.01106,0.01000,0.01146,0.00937,0.01176,0.00870,0.01194,0.00800,0.01200,-0.00800,0.01200,-0.00869,0.01194,-0.00937,0.01176,-0.01000,0.01146,-0.01057,0.01106,-0.01106,0.01057,-0.01146,0.01000,-0.01176,0.00937,-0.01194,0.00870,-0.01200,0.00800,0.00000*
%
%AMMACRO21_1*
4,1,40,0.00800,0.01200,-0.00800,0.01200,-0.00869,0.01194,-0.00937,0.01176,-0.01000,0.01146,-0.01057,0.01106,-0.01106,0.01057,-0.01146,0.01000,-0.01176,0.00937,-0.01194,0.00870,-0.01200,0.00800,-0.01200,-0.00800,-0.01194,-0.00869,-0.01176,-0.00937,-0.01146,-0.01000,-0.01106,-0.01057,-0.01057,-0.01106,-0.01000,-0.01146,-0.00937,-0.01176,-0.00869,-0.01194,-0.00800,-0.01200,0.00800,-0.01200,0.00870,-0.01194,0.00937,-0.01176,0.01000,-0.01146,0.01057,-0.01106,0.01106,-0.01057,0.01146,-0.01000,0.01176,-0.00937,0.01194,-0.00869,0.01200,-0.00800,0.01200,0.00800,0.01194,0.00870,0.01176,0.00937,0.01146,0.01000,0.01106,0.01057,0.01057,0.01106,0.01000,0.01146,0.00937,0.01176,0.00870,0.01194,0.00800,0.01200,0.00000*
%
%AMMACRO33*
4,1,40,-0.00700,-0.01100,0.00700,-0.01100,0.00770,-0.01094,0.00837,-0.01076,0.00900,-0.01046,0.00957,-0.01006,0.01006,-0.00957,0.01046,-0.00900,0.01076,-0.00837,0.01094,-0.00769,0.01100,-0.00700,0.01100,0.00700,0.01094,0.00770,0.01076,0.00837,0.01046,0.00900,0.01006,0.00957,0.00957,0.01006,0.00900,0.01046,0.00837,0.01076,0.00770,0.01094,0.00700,0.01100,-0.00700,0.01100,-0.00769,0.01094,-0.00837,0.01076,-0.00900,0.01046,-0.00957,0.01006,-0.01006,0.00957,-0.01046,0.00900,-0.01076,0.00837,-0.01094,0.00770,-0.01100,0.00700,-0.01100,-0.00700,-0.01094,-0.00769,-0.01076,-0.00837,-0.01046,-0.00900,-0.01006,-0.00957,-0.00957,-0.01006,-0.00900,-0.01046,-0.00837,-0.01076,-0.00769,-0.01094,-0.00700,-0.01100,0.00000*
%
%AMMACRO29_1*
4,1,40,-0.00800,-0.01200,0.00800,-0.01200,0.00870,-0.01194,0.00937,-0.01176,0.01000,-0.01146,0.01057,-0.01106,0.01106,-0.01057,0.01146,-0.01000,0.01176,-0.00937,0.01194,-0.00869,0.01200,-0.00800,0.01200,0.00800,0.01194,0.00870,0.01176,0.00937,0.01146,0.01000,0.01106,0.01057,0.01057,0.01106,0.01000,0.01146,0.00937,0.01176,0.00870,0.01194,0.00800,0.01200,-0.00800,0.01200,-0.00869,0.01194,-0.00937,0.01176,-0.01000,0.01146,-0.01057,0.01106,-0.01106,0.01057,-0.01146,0.01000,-0.01176,0.00937,-0.01194,0.00870,-0.01200,0.00800,-0.01200,-0.00800,-0.01194,-0.00869,-0.01176,-0.00937,-0.01146,-0.01000,-0.01106,-0.01057,-0.01057,-0.01106,-0.01000,-0.01146,-0.00937,-0.01176,-0.00869,-0.01194,-0.00800,-0.01200,0.00000*
%
%AMMACRO13_1*
4,1,40,0.01200,-0.00800,0.01200,0.00800,0.01194,0.00870,0.01176,0.00937,0.01146,0.01000,0.01106,0.01057,0.01057,0.01106,0.01000,0.01146,0.00937,0.01176,0.00870,0.01194,0.00800,0.01200,-0.00800,0.01200,-0.00869,0.01194,-0.00937,0.01176,-0.01000,0.01146,-0.01057,0.01106,-0.01106,0.01057,-0.01146,0.01000,-0.01176,0.00937,-0.01194,0.00870,-0.01200,0.00800,-0.01200,-0.00800,-0.01194,-0.00869,-0.01176,-0.00937,-0.01146,-0.01000,-0.01106,-0.01057,-0.01057,-0.01106,-0.01000,-0.01146,-0.00937,-0.01176,-0.00869,-0.01194,-0.00800,-0.01200,0.00800,-0.01200,0.00870,-0.01194,0.00937,-0.01176,0.01000,-0.01146,0.01057,-0.01106,0.01106,-0.01057,0.01146,-0.01000,0.01176,-0.00937,0.01194,-0.00869,0.01200,-0.00800,0.00000*
%
%AMMACRO26_1*
4,1,40,-0.01100,0.00700,-0.01100,-0.00700,-0.01094,-0.00769,-0.01076,-0.00837,-0.01046,-0.00900,-0.01006,-0.00957,-0.00957,-0.01006,-0.00900,-0.01046,-0.00837,-0.01076,-0.00769,-0.01094,-0.00700,-0.01100,0.00700,-0.01100,0.00770,-0.01094,0.00837,-0.01076,0.00900,-0.01046,0.00957,-0.01006,0.01006,-0.00957,0.01046,-0.00900,0.01076,-0.00837,0.01094,-0.00769,0.01100,-0.00700,0.01100,0.00700,0.01094,0.00770,0.01076,0.00837,0.01046,0.00900,0.01006,0.00957,0.00957,0.01006,0.00900,0.01046,0.00837,0.01076,0.00770,0.01094,0.00700,0.01100,-0.00700,0.01100,-0.00769,0.01094,-0.00837,0.01076,-0.00900,0.01046,-0.00957,0.01006,-0.01006,0.00957,-0.01046,0.00900,-0.01076,0.00837,-0.01094,0.00770,-0.01100,0.00700,0.00000*
%
%AMMACRO44*
4,1,40,0.01300,0.01700,-0.01300,0.01700,-0.01369,0.01694,-0.01437,0.01676,-0.01500,0.01646,-0.01557,0.01606,-0.01606,0.01557,-0.01646,0.01500,-0.01676,0.01437,-0.01694,0.01370,-0.01700,0.01300,-0.01700,-0.01300,-0.01694,-0.01369,-0.01676,-0.01437,-0.01646,-0.01500,-0.01606,-0.01557,-0.01557,-0.01606,-0.01500,-0.01646,-0.01437,-0.01676,-0.01369,-0.01694,-0.01300,-0.01700,0.01300,-0.01700,0.01370,-0.01694,0.01437,-0.01676,0.01500,-0.01646,0.01557,-0.01606,0.01606,-0.01557,0.01646,-0.01500,0.01676,-0.01437,0.01694,-0.01369,0.01700,-0.01300,0.01700,0.01300,0.01694,0.01370,0.01676,0.01437,0.01646,0.01500,0.01606,0.01557,0.01557,0.01606,0.01500,0.01646,0.01437,0.01676,0.01370,0.01694,0.01300,0.01700,0.00000*
%
%AMMACRO41_1*
4,1,3,0.02500,0.01250,0.00000,-0.01250,-0.02500,0.01250,0.02500,0.01250,0.00000*
%
%AMMACRO49*
4,1,40,-0.01700,0.01300,-0.01700,-0.01300,-0.01694,-0.01369,-0.01676,-0.01437,-0.01646,-0.01500,-0.01606,-0.01557,-0.01557,-0.01606,-0.01500,-0.01646,-0.01437,-0.01676,-0.01369,-0.01694,-0.01300,-0.01700,0.01300,-0.01700,0.01370,-0.01694,0.01437,-0.01676,0.01500,-0.01646,0.01557,-0.01606,0.01606,-0.01557,0.01646,-0.01500,0.01676,-0.01437,0.01694,-0.01369,0.01700,-0.01300,0.01700,0.01300,0.01694,0.01370,0.01676,0.01437,0.01646,0.01500,0.01606,0.01557,0.01557,0.01606,0.01500,0.01646,0.01437,0.01676,0.01370,0.01694,0.01300,0.01700,-0.01300,0.01700,-0.01369,0.01694,-0.01437,0.01676,-0.01500,0.01646,-0.01557,0.01606,-0.01606,0.01557,-0.01646,0.01500,-0.01676,0.01437,-0.01694,0.01370,-0.01700,0.01300,0.00000*
%
%AMMACRO39*
4,1,40,0.01100,-0.00700,0.01100,0.00700,0.01094,0.00770,0.01076,0.00837,0.01046,0.00900,0.01006,0.00957,0.00957,0.01006,0.00900,0.01046,0.00837,0.01076,0.00770,0.01094,0.00700,0.01100,-0.00700,0.01100,-0.00769,0.01094,-0.00837,0.01076,-0.00900,0.01046,-0.00957,0.01006,-0.01006,0.00957,-0.01046,0.00900,-0.01076,0.00837,-0.01094,0.00770,-0.01100,0.00700,-0.01100,-0.00700,-0.01094,-0.00769,-0.01076,-0.00837,-0.01046,-0.00900,-0.01006,-0.00957,-0.00957,-0.01006,-0.00900,-0.01046,-0.00837,-0.01076,-0.00769,-0.01094,-0.00700,-0.01100,0.00700,-0.01100,0.00770,-0.01094,0.00837,-0.01076,0.00900,-0.01046,0.00957,-0.01006,0.01006,-0.00957,0.01046,-0.00900,0.01076,-0.00837,0.01094,-0.00769,0.01100,-0.00700,0.00000*
%
%AMMACRO50*
4,1,40,-0.01700,0.01300,-0.01700,-0.01300,-0.01694,-0.01369,-0.01676,-0.01437,-0.01646,-0.01500,-0.01606,-0.01557,-0.01557,-0.01606,-0.01500,-0.01646,-0.01437,-0.01676,-0.01369,-0.01694,-0.01300,-0.01700,0.01300,-0.01700,0.01370,-0.01694,0.01437,-0.01676,0.01500,-0.01646,0.01557,-0.01606,0.01606,-0.01557,0.01646,-0.01500,0.01676,-0.01437,0.01694,-0.01369,0.01700,-0.01300,0.01700,0.01300,0.01694,0.01370,0.01676,0.01437,0.01646,0.01500,0.01606,0.01557,0.01557,0.01606,0.01500,0.01646,0.01437,0.01676,0.01370,0.01694,0.01300,0.01700,-0.01300,0.01700,-0.01369,0.01694,-0.01437,0.01676,-0.01500,0.01646,-0.01557,0.01606,-0.01606,0.01557,-0.01646,0.01500,-0.01676,0.01437,-0.01694,0.01370,-0.01700,0.01300,0.00000*
%
%AMMACRO40_1*
4,1,3,0.00000,0.01250,0.02500,-0.01250,-0.02500,-0.01250,0.00000,0.01250,0.00000*
%
%AMMACRO12*
4,1,40,0.01200,-0.00800,0.01200,0.00800,0.01194,0.00870,0.01176,0.00937,0.01146,0.01000,0.01106,0.01057,0.01057,0.01106,0.01000,0.01146,0.00937,0.01176,0.00870,0.01194,0.00800,0.01200,-0.00800,0.01200,-0.00869,0.01194,-0.00937,0.01176,-0.01000,0.01146,-0.01057,0.01106,-0.01106,0.01057,-0.01146,0.01000,-0.01176,0.00937,-0.01194,0.00870,-0.01200,0.00800,-0.01200,-0.00800,-0.01194,-0.00869,-0.01176,-0.00937,-0.01146,-0.01000,-0.01106,-0.01057,-0.01057,-0.01106,-0.01000,-0.01146,-0.00937,-0.01176,-0.00869,-0.01194,-0.00800,-0.01200,0.00800,-0.01200,0.00870,-0.01194,0.00937,-0.01176,0.01000,-0.01146,0.01057,-0.01106,0.01106,-0.01057,0.01146,-0.01000,0.01176,-0.00937,0.01194,-0.00869,0.01200,-0.00800,0.00000*
%
%AMMACRO36*
4,1,20,-0.06350,0.10750,-0.04900,0.10750,-0.04900,0.11800,-0.03950,0.11800,-0.03950,0.10750,0.03950,0.10750,0.03950,0.11800,0.04900,0.11800,0.04900,0.10750,0.06350,0.10750,0.06350,-0.10750,0.04900,-0.10750,0.04900,-0.11800,0.03950,-0.11800,0.03950,-0.10750,-0.03950,-0.10750,-0.03950,-0.11800,-0.04900,-0.11800,-0.04900,-0.10750,-0.06350,-0.10750,-0.06350,0.10750,0.00000*
%
%AMMACRO21_1_180*
4,1,40,-0.00800,-0.01200,0.00800,-0.01200,0.00869,-0.01194,0.00937,-0.01176,0.01000,-0.01146,0.01057,-0.01106,0.01106,-0.01057,0.01146,-0.01000,0.01176,-0.00937,0.01194,-0.00870,0.01200,-0.00800,0.01200,0.00800,0.01194,0.00869,0.01176,0.00937,0.01146,0.01000,0.01106,0.01057,0.01057,0.01106,0.01000,0.01146,0.00937,0.01176,0.00869,0.01194,0.00800,0.01200,-0.00800,0.01200,-0.00870,0.01194,-0.00937,0.01176,-0.01000,0.01146,-0.01057,0.01106,-0.01106,0.01057,-0.01146,0.01000,-0.01176,0.00937,-0.01194,0.00869,-0.01200,0.00800,-0.01200,-0.00800,-0.01194,-0.00870,-0.01176,-0.00937,-0.01146,-0.01000,-0.01106,-0.01057,-0.01057,-0.01106,-0.01000,-0.01146,-0.00937,-0.01176,-0.00870,-0.01194,-0.00800,-0.01200,0.00000*
%
%AMMACRO13_1_180*
4,1,40,-0.01200,0.00800,-0.01200,-0.00800,-0.01194,-0.00870,-0.01176,-0.00937,-0.01146,-0.01000,-0.01106,-0.01057,-0.01057,-0.01106,-0.01000,-0.01146,-0.00937,-0.01176,-0.00870,-0.01194,-0.00800,-0.01200,0.00800,-0.01200,0.00869,-0.01194,0.00937,-0.01176,0.01000,-0.01146,0.01057,-0.01106,0.01106,-0.01057,0.01146,-0.01000,0.01176,-0.00937,0.01194,-0.00870,0.01200,-0.00800,0.01200,0.00800,0.01194,0.00869,0.01176,0.00937,0.01146,0.01000,0.01106,0.01057,0.01057,0.01106,0.01000,0.01146,0.00937,0.01176,0.00869,0.01194,0.00800,0.01200,-0.00800,0.01200,-0.00870,0.01194,-0.00937,0.01176,-0.01000,0.01146,-0.01057,0.01106,-0.01106,0.01057,-0.01146,0.01000,-0.01176,0.00937,-0.01194,0.00869,-0.01200,0.00800,0.00000*
%
%AMMACRO32_180*
4,1,40,0.01200,-0.00800,0.01200,0.00800,0.01194,0.00869,0.01176,0.00937,0.01146,0.01000,0.01106,0.01057,0.01057,0.01106,0.01000,0.01146,0.00937,0.01176,0.00869,0.01194,0.00800,0.01200,-0.00800,0.01200,-0.00870,0.01194,-0.00937,0.01176,-0.01000,0.01146,-0.01057,0.01106,-0.01106,0.01057,-0.01146,0.01000,-0.01176,0.00937,-0.01194,0.00869,-0.01200,0.00800,-0.01200,-0.00800,-0.01194,-0.00870,-0.01176,-0.00937,-0.01146,-0.01000,-0.01106,-0.01057,-0.01057,-0.01106,-0.01000,-0.01146,-0.00937,-0.01176,-0.00870,-0.01194,-0.00800,-0.01200,0.00800,-0.01200,0.00869,-0.01194,0.00937,-0.01176,0.01000,-0.01146,0.01057,-0.01106,0.01106,-0.01057,0.01146,-0.01000,0.01176,-0.00937,0.01194,-0.00870,0.01200,-0.00800,0.00000*
%
%AMMACRO22_1_180*
4,1,20,0.04700,0.03200,0.04700,0.01550,0.07400,0.01550,0.07400,0.00450,0.04900,0.00450,0.04900,-0.00450,0.07400,-0.00450,0.07400,-0.01550,0.04700,-0.01550,0.04700,-0.03200,-0.04700,-0.03200,-0.04700,-0.01550,-0.07400,-0.01550,-0.07400,-0.00450,-0.04900,-0.00450,-0.04900,0.00450,-0.07400,0.00450,-0.07400,0.01550,-0.04700,0.01550,-0.04700,0.03200,0.04700,0.03200,0.00000*
%
%AMMACRO40_180*
4,1,40,-0.01100,0.00700,-0.01100,-0.00700,-0.01094,-0.00770,-0.01076,-0.00837,-0.01046,-0.00900,-0.01006,-0.00957,-0.00957,-0.01006,-0.00900,-0.01046,-0.00837,-0.01076,-0.00770,-0.01094,-0.00700,-0.01100,0.00700,-0.01100,0.00769,-0.01094,0.00837,-0.01076,0.00900,-0.01046,0.00957,-0.01006,0.01006,-0.00957,0.01046,-0.00900,0.01076,-0.00837,0.01094,-0.00770,0.01100,-0.00700,0.01100,0.00700,0.01094,0.00769,0.01076,0.00837,0.01046,0.00900,0.01006,0.00957,0.00957,0.01006,0.00900,0.01046,0.00837,0.01076,0.00769,0.01094,0.00700,0.01100,-0.00700,0.01100,-0.00770,0.01094,-0.00837,0.01076,-0.00900,0.01046,-0.00957,0.01006,-0.01006,0.00957,-0.01046,0.00900,-0.01076,0.00837,-0.01094,0.00769,-0.01100,0.00700,0.00000*
%
%AMMACRO24_1_180*
4,1,40,-0.01700,0.01300,-0.01700,-0.01300,-0.01694,-0.01370,-0.01676,-0.01437,-0.01646,-0.01500,-0.01606,-0.01557,-0.01557,-0.01606,-0.01500,-0.01646,-0.01437,-0.01676,-0.01370,-0.01694,-0.01300,-0.01700,0.01300,-0.01700,0.01369,-0.01694,0.01437,-0.01676,0.01500,-0.01646,0.01557,-0.01606,0.01606,-0.01557,0.01646,-0.01500,0.01676,-0.01437,0.01694,-0.01370,0.01700,-0.01300,0.01700,0.01300,0.01694,0.01369,0.01676,0.01437,0.01646,0.01500,0.01606,0.01557,0.01557,0.01606,0.01500,0.01646,0.01437,0.01676,0.01369,0.01694,0.01300,0.01700,-0.01300,0.01700,-0.01370,0.01694,-0.01437,0.01676,-0.01500,0.01646,-0.01557,0.01606,-0.01606,0.01557,-0.01646,0.01500,-0.01676,0.01437,-0.01694,0.01369,-0.01700,0.01300,0.00000*
%
%AMMACRO33_180*
4,1,40,0.00700,0.01100,-0.00700,0.01100,-0.00770,0.01094,-0.00837,0.01076,-0.00900,0.01046,-0.00957,0.01006,-0.01006,0.00957,-0.01046,0.00900,-0.01076,0.00837,-0.01094,0.00769,-0.01100,0.00700,-0.01100,-0.00700,-0.01094,-0.00770,-0.01076,-0.00837,-0.01046,-0.00900,-0.01006,-0.00957,-0.00957,-0.01006,-0.00900,-0.01046,-0.00837,-0.01076,-0.00770,-0.01094,-0.00700,-0.01100,0.00700,-0.01100,0.00769,-0.01094,0.00837,-0.01076,0.00900,-0.01046,0.00957,-0.01006,0.01006,-0.00957,0.01046,-0.00900,0.01076,-0.00837,0.01094,-0.00770,0.01100,-0.00700,0.01100,0.00700,0.01094,0.00769,0.01076,0.00837,0.01046,0.00900,0.01006,0.00957,0.00957,0.01006,0.00900,0.01046,0.00837,0.01076,0.00769,0.01094,0.00700,0.01100,0.00000*
%
%AMMACRO16_1_180*
4,1,40,-0.00700,-0.01100,0.00700,-0.01100,0.00769,-0.01094,0.00837,-0.01076,0.00900,-0.01046,0.00957,-0.01006,0.01006,-0.00957,0.01046,-0.00900,0.01076,-0.00837,0.01094,-0.00770,0.01100,-0.00700,0.01100,0.00700,0.01094,0.00769,0.01076,0.00837,0.01046,0.00900,0.01006,0.00957,0.00957,0.01006,0.00900,0.01046,0.00837,0.01076,0.00769,0.01094,0.00700,0.01100,-0.00700,0.01100,-0.00770,0.01094,-0.00837,0.01076,-0.00900,0.01046,-0.00957,0.01006,-0.01006,0.00957,-0.01046,0.00900,-0.01076,0.00837,-0.01094,0.00769,-0.01100,0.00700,-0.01100,-0.00700,-0.01094,-0.00770,-0.01076,-0.00837,-0.01046,-0.00900,-0.01006,-0.00957,-0.00957,-0.01006,-0.00900,-0.01046,-0.00837,-0.01076,-0.00770,-0.01094,-0.00700,-0.01100,0.00000*
%
%AMMACRO26_1_180*
4,1,40,0.01100,-0.00700,0.01100,0.00700,0.01094,0.00769,0.01076,0.00837,0.01046,0.00900,0.01006,0.00957,0.00957,0.01006,0.00900,0.01046,0.00837,0.01076,0.00769,0.01094,0.00700,0.01100,-0.00700,0.01100,-0.00770,0.01094,-0.00837,0.01076,-0.00900,0.01046,-0.00957,0.01006,-0.01006,0.00957,-0.01046,0.00900,-0.01076,0.00837,-0.01094,0.00769,-0.01100,0.00700,-0.01100,-0.00700,-0.01094,-0.00770,-0.01076,-0.00837,-0.01046,-0.00900,-0.01006,-0.00957,-0.00957,-0.01006,-0.00900,-0.01046,-0.00837,-0.01076,-0.00770,-0.01094,-0.00700,-0.01100,0.00700,-0.01100,0.00769,-0.01094,0.00837,-0.01076,0.00900,-0.01046,0.00957,-0.01006,0.01006,-0.00957,0.01046,-0.00900,0.01076,-0.00837,0.01094,-0.00770,0.01100,-0.00700,0.00000*
%
%AMMACRO29_1_180*
4,1,40,0.00800,0.01200,-0.00800,0.01200,-0.00870,0.01194,-0.00937,0.01176,-0.01000,0.01146,-0.01057,0.01106,-0.01106,0.01057,-0.01146,0.01000,-0.01176,0.00937,-0.01194,0.00869,-0.01200,0.00800,-0.01200,-0.00800,-0.01194,-0.00870,-0.01176,-0.00937,-0.01146,-0.01000,-0.01106,-0.01057,-0.01057,-0.01106,-0.01000,-0.01146,-0.00937,-0.01176,-0.00870,-0.01194,-0.00800,-0.01200,0.00800,-0.01200,0.00869,-0.01194,0.00937,-0.01176,0.01000,-0.01146,0.01057,-0.01106,0.01106,-0.01057,0.01146,-0.01000,0.01176,-0.00937,0.01194,-0.00870,0.01200,-0.00800,0.01200,0.00800,0.01194,0.00869,0.01176,0.00937,0.01146,0.01000,0.01106,0.01057,0.01057,0.01106,0.01000,0.01146,0.00937,0.01176,0.00869,0.01194,0.00800,0.01200,0.00000*
%
%AMMACRO46_180*
4,1,40,-0.01300,-0.01700,0.01300,-0.01700,0.01369,-0.01694,0.01437,-0.01676,0.01500,-0.01646,0.01557,-0.01606,0.01606,-0.01557,0.01646,-0.01500,0.01676,-0.01437,0.01694,-0.01370,0.01700,-0.01300,0.01700,0.01300,0.01694,0.01369,0.01676,0.01437,0.01646,0.01500,0.01606,0.01557,0.01557,0.01606,0.01500,0.01646,0.01437,0.01676,0.01369,0.01694,0.01300,0.01700,-0.01300,0.01700,-0.01370,0.01694,-0.01437,0.01676,-0.01500,0.01646,-0.01557,0.01606,-0.01606,0.01557,-0.01646,0.01500,-0.01676,0.01437,-0.01694,0.01369,-0.01700,0.01300,-0.01700,-0.01300,-0.01694,-0.01370,-0.01676,-0.01437,-0.01646,-0.01500,-0.01606,-0.01557,-0.01557,-0.01606,-0.01500,-0.01646,-0.01437,-0.01676,-0.01370,-0.01694,-0.01300,-0.01700,0.00000*
%
%AMMACRO12_180*
4,1,40,-0.01200,0.00800,-0.01200,-0.00800,-0.01194,-0.00870,-0.01176,-0.00937,-0.01146,-0.01000,-0.01106,-0.01057,-0.01057,-0.01106,-0.01000,-0.01146,-0.00937,-0.01176,-0.00870,-0.01194,-0.00800,-0.01200,0.00800,-0.01200,0.00869,-0.01194,0.00937,-0.01176,0.01000,-0.01146,0.01057,-0.01106,0.01106,-0.01057,0.01146,-0.01000,0.01176,-0.00937,0.01194,-0.00870,0.01200,-0.00800,0.01200,0.00800,0.01194,0.00869,0.01176,0.00937,0.01146,0.01000,0.01106,0.01057,0.01057,0.01106,0.01000,0.01146,0.00937,0.01176,0.00869,0.01194,0.00800,0.01200,-0.00800,0.01200,-0.00870,0.01194,-0.00937,0.01176,-0.01000,0.01146,-0.01057,0.01106,-0.01106,0.01057,-0.01146,0.01000,-0.01176,0.00937,-0.01194,0.00869,-0.01200,0.00800,0.00000*
%
%AMMACRO40_1_180*
4,1,3,0.00000,-0.01250,-0.02500,0.01250,0.02500,0.01250,0.00000,-0.01250,0.00000*
%
%AMMACRO50_180*
4,1,40,0.01700,-0.01300,0.01700,0.01300,0.01694,0.01369,0.01676,0.01437,0.01646,0.01500,0.01606,0.01557,0.01557,0.01606,0.01500,0.01646,0.01437,0.01676,0.01369,0.01694,0.01300,0.01700,-0.01300,0.01700,-0.01370,0.01694,-0.01437,0.01676,-0.01500,0.01646,-0.01557,0.01606,-0.01606,0.01557,-0.01646,0.01500,-0.01676,0.01437,-0.01694,0.01369,-0.01700,0.01300,-0.01700,-0.01300,-0.01694,-0.01370,-0.01676,-0.01437,-0.01646,-0.01500,-0.01606,-0.01557,-0.01557,-0.01606,-0.01500,-0.01646,-0.01437,-0.01676,-0.01370,-0.01694,-0.01300,-0.01700,0.01300,-0.01700,0.01369,-0.01694,0.01437,-0.01676,0.01500,-0.01646,0.01557,-0.01606,0.01606,-0.01557,0.01646,-0.01500,0.01676,-0.01437,0.01694,-0.01370,0.01700,-0.01300,0.00000*
%
%AMMACRO41_1_180*
4,1,3,-0.02500,-0.01250,0.00000,0.01250,0.02500,-0.01250,-0.02500,-0.01250,0.00000*
%
%AMMACRO44_180*
4,1,40,-0.01300,-0.01700,0.01300,-0.01700,0.01369,-0.01694,0.01437,-0.01676,0.01500,-0.01646,0.01557,-0.01606,0.01606,-0.01557,0.01646,-0.01500,0.01676,-0.01437,0.01694,-0.01370,0.01700,-0.01300,0.01700,0.01300,0.01694,0.01369,0.01676,0.01437,0.01646,0.01500,0.01606,0.01557,0.01557,0.01606,0.01500,0.01646,0.01437,0.01676,0.01369,0.01694,0.01300,0.01700,-0.01300,0.01700,-0.01370,0.01694,-0.01437,0.01676,-0.01500,0.01646,-0.01557,0.01606,-0.01606,0.01557,-0.01646,0.01500,-0.01676,0.01437,-0.01694,0.01369,-0.01700,0.01300,-0.01700,-0.01300,-0.01694,-0.01370,-0.01676,-0.01437,-0.01646,-0.01500,-0.01606,-0.01557,-0.01557,-0.01606,-0.01500,-0.01646,-0.01437,-0.01676,-0.01370,-0.01694,-0.01300,-0.01700,0.00000*
%
%AMMACRO36_180*
4,1,20,0.06350,-0.10750,0.04900,-0.10750,0.04900,-0.11800,0.03950,-0.11800,0.03950,-0.10750,-0.03950,-0.10750,-0.03950,-0.11800,-0.04900,-0.11800,-0.04900,-0.10750,-0.06350,-0.10750,-0.06350,0.10750,-0.04900,0.10750,-0.04900,0.11800,-0.03950,0.11800,-0.03950,0.10750,0.03950,0.10750,0.03950,0.11800,0.04900,0.11800,0.04900,0.10750,0.06350,0.10750,0.06350,-0.10750,0.00000*
%
%AMMACRO39_180*
4,1,40,-0.01100,0.00700,-0.01100,-0.00700,-0.01094,-0.00770,-0.01076,-0.00837,-0.01046,-0.00900,-0.01006,-0.00957,-0.00957,-0.01006,-0.00900,-0.01046,-0.00837,-0.01076,-0.00770,-0.01094,-0.00700,-0.01100,0.00700,-0.01100,0.00769,-0.01094,0.00837,-0.01076,0.00900,-0.01046,0.00957,-0.01006,0.01006,-0.00957,0.01046,-0.00900,0.01076,-0.00837,0.01094,-0.00770,0.01100,-0.00700,0.01100,0.00700,0.01094,0.00769,0.01076,0.00837,0.01046,0.00900,0.01006,0.00957,0.00957,0.01006,0.00900,0.01046,0.00837,0.01076,0.00769,0.01094,0.00700,0.01100,-0.00700,0.01100,-0.00770,0.01094,-0.00837,0.01076,-0.00900,0.01046,-0.00957,0.01006,-0.01006,0.00957,-0.01046,0.00900,-0.01076,0.00837,-0.01094,0.00769,-0.01100,0.00700,0.00000*
%
%AMMACRO49_180*
4,1,40,0.01700,-0.01300,0.01700,0.01300,0.01694,0.01369,0.01676,0.01437,0.01646,0.01500,0.01606,0.01557,0.01557,0.01606,0.01500,0.01646,0.01437,0.01676,0.01369,0.01694,0.01300,0.01700,-0.01300,0.01700,-0.01370,0.01694,-0.01437,0.01676,-0.01500,0.01646,-0.01557,0.01606,-0.01606,0.01557,-0.01646,0.01500,-0.01676,0.01437,-0.01694,0.01369,-0.01700,0.01300,-0.01700,-0.01300,-0.01694,-0.01370,-0.01676,-0.01437,-0.01646,-0.01500,-0.01606,-0.01557,-0.01557,-0.01606,-0.01500,-0.01646,-0.01437,-0.01676,-0.01370,-0.01694,-0.01300,-0.01700,0.01300,-0.01700,0.01369,-0.01694,0.01437,-0.01676,0.01500,-0.01646,0.01557,-0.01606,0.01606,-0.01557,0.01646,-0.01500,0.01676,-0.01437,0.01694,-0.01370,0.01700,-0.01300,0.00000*
%
%ADD11C,0.08600*%
%ADD13C,0.02800*%
%ADD22R,0.05500X0.04500*%
%ADD29R,0.04500X0.05500*%
%ADD33R,0.01600X0.04800*%
%ADD40C,0.02000*%
%ADD41C,0.00600*%
%ADD46C,0.04000*%
%ADD51MACRO46*%
%ADD52MACRO24_1*%
%ADD53R,0.10200X0.05300*%
%ADD55R,0.10800X0.04700*%
%ADD58MACRO40*%
%ADD59MACRO16_1*%
%ADD60MACRO22_1*%
%ADD61MACRO32*%
%ADD62MACRO21_1*%
%ADD67R,0.06000X0.01200*%
%ADD68R,0.06100X0.01200*%
%ADD69R,0.01200X0.06000*%
%ADD74R,0.06000X0.01400*%
%ADD75R,0.04400X0.01200*%
%ADD76R,0.01400X0.06000*%
%ADD77R,0.01200X0.03600*%
%ADD78R,0.09500X0.09000*%
%ADD79MACRO33*%
%ADD80MACRO29_1*%
%ADD81MACRO13_1*%
%ADD82MACRO26_1*%
%ADD89MACRO44*%
%ADD90MACRO41_1*%
%ADD91MACRO49*%
%ADD92MACRO39*%
%ADD93MACRO50*%
%ADD94MACRO40_1*%
%ADD95MACRO12*%
%ADD96MACRO36*%
%ADD162R,0.05500X0.04500*%
%ADD165R,0.01600X0.04800*%
%ADD179R,0.04500X0.05500*%
%ADD185MACRO21_1_180*%
%ADD186R,0.01200X0.06000*%
%ADD187MACRO13_1_180*%
%ADD188MACRO32_180*%
%ADD189MACRO22_1_180*%
%ADD190MACRO40_180*%
%ADD191MACRO24_1_180*%
%ADD193MACRO33_180*%
%ADD196MACRO16_1_180*%
%ADD197R,0.10800X0.04700*%
%ADD198MACRO26_1_180*%
%ADD199R,0.06000X0.01200*%
%ADD201R,0.10200X0.05300*%
%ADD203R,0.01200X0.03600*%
%ADD204R,0.01400X0.06000*%
%ADD206MACRO29_1_180*%
%ADD207MACRO46_180*%
%ADD209R,0.06000X0.01400*%
%ADD210R,0.04400X0.01200*%
%ADD211R,0.06100X0.01200*%
%ADD212R,0.09500X0.09000*%
%ADD213MACRO12_180*%
%ADD214MACRO40_1_180*%
%ADD215MACRO50_180*%
%ADD216MACRO41_1_180*%
%ADD217MACRO44_180*%
%ADD218MACRO36_180*%
%ADD219MACRO39_180*%
%ADD220MACRO49_180*%
%LNTSMD.art*%
%LPD*%
G54D11*
X26087Y-114844D03*
X26435Y373984D03*
X175335Y62719D03*
Y189062D03*
X547104Y69007D03*
Y195351D03*
X696192Y373984D03*
G54D62*
X63000Y299889D03*
X103000Y280700D03*
X100500Y338889D03*
X109500Y283200D03*
X130000Y291700D03*
X203600Y296200D03*
X290000Y159700D03*
G54D46*
X22401Y341025D03*
X291000Y22500D03*
X316610Y341025D03*
G54D95*
X56200Y325189D03*
X67200Y302689D03*
X207300Y300200D03*
X233700Y67000D03*
Y75000D03*
Y71000D03*
Y122000D03*
Y126000D03*
Y138500D03*
Y130000D03*
Y134500D03*
Y175500D03*
Y183500D03*
Y179500D03*
Y238500D03*
Y243000D03*
Y230500D03*
Y234500D03*
Y247000D03*
G54D61*
X103800Y310000D03*
G54D60*
X71500Y315689D03*
G54D52*
X58000Y320489D03*
X169500Y336300D03*
X196000Y341300D03*
G54D79*
X100200Y317000D03*
Y321000D03*
X298200Y249000D03*
G54D94*
X185811Y298150D03*
G54D13*
X53500Y320689D03*
X71000Y294189D03*
X66750Y289689D03*
X59000Y304189D03*
X68000Y339189D03*
X58000Y337439D03*
X77500Y338000D03*
X95000Y289000D03*
X94500Y303100D03*
X96500Y332500D03*
X117913Y287300D03*
X122500Y285500D03*
X110500Y306000D03*
X123500Y304700D03*
X128500Y304500D03*
X162311Y298500D03*
X194811Y303500D03*
X207500Y296250D03*
X258000Y160500D03*
X299500Y144900D03*
X298500Y254000D03*
G54D79*
X96800Y317000D03*
Y321000D03*
X294800Y249000D03*
G54D29*
X58200Y331189D03*
X65800D03*
X76700Y285689D03*
X84300D03*
X76700Y293689D03*
X84300D03*
X76700Y301689D03*
X84300D03*
X76700Y331189D03*
X84300D03*
X255200Y296000D03*
Y304000D03*
X262800Y296000D03*
Y304000D03*
G54D93*
X297000Y123800D03*
G54D90*
X185811Y300850D03*
G54D52*
X58000Y314889D03*
X169500Y330700D03*
X196000Y335700D03*
G54D82*
X62000Y337489D03*
X95000Y280800D03*
X99000D03*
X114500Y281800D03*
X119000Y280300D03*
Y308300D03*
X115000D03*
X123500D03*
X127500D03*
X168311Y298300D03*
X199811Y296300D03*
X296000Y132300D03*
Y139800D03*
G54D33*
X295440Y162250D03*
X298000D03*
X300560D03*
Y168750D03*
X295440D03*
G54D67*
X123100Y294015D03*
Y292045D03*
X113900D03*
Y294015D03*
X123100Y297955D03*
Y295985D03*
X113900D03*
Y297955D03*
G54D59*
X63300Y294189D03*
X67300Y298689D03*
X70800Y345000D03*
X96800Y325000D03*
X192111Y299500D03*
X204111Y304000D03*
X294800Y245000D03*
G54D53*
X206943Y324000D03*
X232057D03*
G54D82*
X62000Y340889D03*
X95000Y284200D03*
X99000D03*
X114500Y285200D03*
X119000Y283700D03*
Y311700D03*
X115000D03*
X123500D03*
X127500D03*
X168311Y301700D03*
X199811Y299700D03*
X296000Y135700D03*
Y143200D03*
G54D51*
X208200Y292000D03*
G54D76*
X107325Y320089D03*
X109880D03*
X112440D03*
X115000D03*
X117560D03*
X120120D03*
X122675D03*
Y342289D03*
X120120D03*
X117560D03*
X115000D03*
X112440D03*
X109880D03*
X107325D03*
G54D59*
X66700Y294189D03*
X70700Y298689D03*
X74200Y345000D03*
X100200Y325000D03*
X195511Y299500D03*
X207511Y304000D03*
X298200Y245000D03*
G54D80*
X71500Y329389D03*
X165000Y308200D03*
X249000Y144200D03*
Y252700D03*
G54D22*
X139000Y312200D03*
Y319800D03*
Y329200D03*
Y336800D03*
X147000Y312200D03*
X155000D03*
X147000Y319800D03*
X155000D03*
Y329200D03*
Y336800D03*
X147000Y329200D03*
Y336800D03*
X163000Y329200D03*
Y336800D03*
X189500Y336200D03*
Y343800D03*
G54D77*
X67565Y309589D03*
X69530D03*
X71500D03*
Y321789D03*
X69530D03*
X67565D03*
X73470Y309589D03*
X75435D03*
Y321789D03*
X73470D03*
G54D89*
X213800Y292000D03*
G54D81*
X70800Y302689D03*
X59800Y325189D03*
X210900Y300200D03*
X237300Y67000D03*
Y75000D03*
Y71000D03*
Y122000D03*
Y126000D03*
Y138500D03*
Y130000D03*
Y134500D03*
Y175500D03*
Y183500D03*
Y179500D03*
Y238500D03*
Y243000D03*
Y230500D03*
Y234500D03*
Y247000D03*
G54D96*
X185811Y318500D03*
G54D80*
X71500Y332989D03*
X165000Y311800D03*
X249000Y147800D03*
Y256300D03*
G54D74*
X230410Y154660D03*
Y157220D03*
Y159780D03*
Y162340D03*
X246590D03*
Y159780D03*
Y157220D03*
Y154660D03*
G54D75*
X176168Y308657D03*
Y310626D03*
Y312594D03*
Y314563D03*
Y316531D03*
Y318500D03*
Y320469D03*
Y322437D03*
Y324406D03*
Y326374D03*
Y328343D03*
X195454Y310626D03*
Y308657D03*
Y326374D03*
Y324406D03*
Y322437D03*
Y320469D03*
Y318500D03*
Y316531D03*
Y314563D03*
Y312594D03*
Y328343D03*
G54D69*
X104955Y293900D03*
X102985D03*
X101015D03*
X99045D03*
Y303100D03*
X101015D03*
X102985D03*
X104955D03*
G54D68*
X256594Y68661D03*
Y70629D03*
Y72598D03*
Y74566D03*
Y84409D03*
Y86377D03*
Y88346D03*
Y90314D03*
Y92283D03*
Y94251D03*
Y96220D03*
Y98188D03*
Y100157D03*
Y102125D03*
Y104094D03*
Y106063D03*
Y108031D03*
Y110000D03*
Y111968D03*
Y113937D03*
Y115905D03*
Y117874D03*
Y119842D03*
Y121811D03*
Y123779D03*
Y125748D03*
Y127716D03*
Y129685D03*
Y131653D03*
Y133622D03*
Y135590D03*
Y137559D03*
Y139527D03*
Y177323D03*
Y179291D03*
Y181260D03*
Y183228D03*
Y193071D03*
Y195039D03*
Y197008D03*
Y198976D03*
Y200945D03*
Y202913D03*
Y204882D03*
Y206850D03*
Y208819D03*
Y210787D03*
Y212756D03*
Y214725D03*
Y216693D03*
Y218662D03*
Y220630D03*
Y222599D03*
Y224567D03*
Y226536D03*
Y228504D03*
Y230473D03*
Y232441D03*
Y234410D03*
Y236378D03*
Y238347D03*
Y240315D03*
Y242284D03*
Y244252D03*
Y246221D03*
Y248189D03*
X286319Y67677D03*
Y69645D03*
Y71614D03*
Y73582D03*
Y75551D03*
Y85393D03*
Y87362D03*
Y89330D03*
Y91299D03*
Y93267D03*
Y95236D03*
Y97204D03*
Y99173D03*
Y101141D03*
Y103110D03*
Y105078D03*
Y107047D03*
Y109015D03*
Y110984D03*
Y112952D03*
Y114921D03*
Y116889D03*
Y118858D03*
Y120826D03*
Y122795D03*
Y124763D03*
Y126732D03*
Y128700D03*
Y130669D03*
Y132637D03*
Y134606D03*
Y136574D03*
Y138543D03*
Y140511D03*
Y176339D03*
Y178307D03*
Y180276D03*
Y182244D03*
Y184213D03*
Y194055D03*
Y196024D03*
Y197992D03*
Y199961D03*
Y201929D03*
Y203898D03*
Y205866D03*
Y207835D03*
Y209803D03*
Y211772D03*
Y213740D03*
Y215709D03*
Y217677D03*
Y219646D03*
Y221614D03*
Y223583D03*
Y225551D03*
Y227520D03*
Y229488D03*
Y231457D03*
Y233425D03*
Y235394D03*
Y237362D03*
Y239331D03*
Y241299D03*
Y243268D03*
Y245236D03*
Y247205D03*
Y249173D03*
G54D62*
X63000Y303489D03*
X103000Y284300D03*
X100500Y342489D03*
X109500Y286800D03*
X130000Y295300D03*
X203600Y299800D03*
X290000Y163300D03*
G54D78*
X249000Y315100D03*
Y339900D03*
G54D61*
X100200Y310000D03*
G54D58*
X176311Y301700D03*
X294000Y154200D03*
X298000D03*
G54D92*
X176311Y298300D03*
X294000Y150800D03*
X298000D03*
G54D55*
X283268Y63346D03*
Y144842D03*
Y172008D03*
Y253504D03*
G54D91*
X297000Y118200D03*
G54D62*
X436031Y299889D03*
X476031Y280700D03*
X473531Y338889D03*
X482531Y283200D03*
X503031Y291700D03*
X576631Y296200D03*
X663031Y159700D03*
G54D46*
X395432Y341025D03*
X664031Y22500D03*
X689641Y341025D03*
G54D95*
X429231Y325189D03*
X440231Y302689D03*
X580331Y300200D03*
X606731Y67000D03*
Y75000D03*
Y71000D03*
Y122000D03*
Y126000D03*
Y138500D03*
Y130000D03*
Y134500D03*
Y175500D03*
Y183500D03*
Y179500D03*
Y238500D03*
Y243000D03*
Y230500D03*
Y234500D03*
Y247000D03*
G54D61*
X476831Y310000D03*
G54D60*
X444531Y315689D03*
G54D52*
X431031Y320489D03*
X542531Y336300D03*
X569031Y341300D03*
G54D79*
X473231Y317000D03*
Y321000D03*
X671231Y249000D03*
G54D94*
X558842Y298150D03*
G54D13*
X426531Y320689D03*
X444031Y294189D03*
X439781Y289689D03*
X432031Y304189D03*
X441031Y339189D03*
X431031Y337439D03*
X450531Y338000D03*
X468031Y289000D03*
X467531Y303100D03*
X469531Y332500D03*
X490944Y287300D03*
X495531Y285500D03*
X483531Y306000D03*
X496531Y304700D03*
X501531Y304500D03*
X535342Y298500D03*
X567842Y303500D03*
X580531Y296250D03*
X631031Y160500D03*
X672531Y144900D03*
X671531Y254000D03*
G54D79*
X469831Y317000D03*
Y321000D03*
X667831Y249000D03*
G54D29*
X431231Y331189D03*
X438831D03*
X449731Y285689D03*
X457331D03*
X449731Y293689D03*
X457331D03*
X449731Y301689D03*
X457331D03*
X449731Y331189D03*
X457331D03*
X628231Y296000D03*
Y304000D03*
X635831Y296000D03*
Y304000D03*
G54D93*
X670031Y123800D03*
G54D90*
X558842Y300850D03*
G54D52*
X431031Y314889D03*
X542531Y330700D03*
X569031Y335700D03*
G54D82*
X435031Y337489D03*
X468031Y280800D03*
X472031D03*
X487531Y281800D03*
X492031Y280300D03*
Y308300D03*
X488031D03*
X496531D03*
X500531D03*
X541342Y298300D03*
X572842Y296300D03*
X669031Y132300D03*
Y139800D03*
G54D33*
X668471Y162250D03*
X671031D03*
X673591D03*
Y168750D03*
X668471D03*
G54D67*
X496131Y294015D03*
Y292045D03*
X486931D03*
Y294015D03*
X496131Y297955D03*
Y295985D03*
X486931D03*
Y297955D03*
G54D59*
X436331Y294189D03*
X440331Y298689D03*
X443831Y345000D03*
X469831Y325000D03*
X565142Y299500D03*
X577142Y304000D03*
X667831Y245000D03*
G54D53*
X579974Y324000D03*
X605088D03*
G54D82*
X435031Y340889D03*
X468031Y284200D03*
X472031D03*
X487531Y285200D03*
X492031Y283700D03*
Y311700D03*
X488031D03*
X496531D03*
X500531D03*
X541342Y301700D03*
X572842Y299700D03*
X669031Y135700D03*
Y143200D03*
G54D51*
X581231Y292000D03*
G54D76*
X480356Y320089D03*
X482911D03*
X485471D03*
X488031D03*
X490591D03*
X493151D03*
X495706D03*
Y342289D03*
X493151D03*
X490591D03*
X488031D03*
X485471D03*
X482911D03*
X480356D03*
G54D59*
X439731Y294189D03*
X443731Y298689D03*
X447231Y345000D03*
X473231Y325000D03*
X568542Y299500D03*
X580542Y304000D03*
X671231Y245000D03*
G54D80*
X444531Y329389D03*
X538031Y308200D03*
X622031Y144200D03*
Y252700D03*
G54D22*
X512031Y312200D03*
Y319800D03*
Y329200D03*
Y336800D03*
X520031Y312200D03*
X528031D03*
X520031Y319800D03*
X528031D03*
Y329200D03*
Y336800D03*
X520031Y329200D03*
Y336800D03*
X536031Y329200D03*
Y336800D03*
X562531Y336200D03*
Y343800D03*
G54D77*
X440596Y309589D03*
X442561D03*
X444531D03*
Y321789D03*
X442561D03*
X440596D03*
X446501Y309589D03*
X448466D03*
Y321789D03*
X446501D03*
G54D89*
X586831Y292000D03*
G54D81*
X443831Y302689D03*
X432831Y325189D03*
X583931Y300200D03*
X610331Y67000D03*
Y75000D03*
Y71000D03*
Y122000D03*
Y126000D03*
Y138500D03*
Y130000D03*
Y134500D03*
Y175500D03*
Y183500D03*
Y179500D03*
Y238500D03*
Y243000D03*
Y230500D03*
Y234500D03*
Y247000D03*
G54D96*
X558842Y318500D03*
G54D80*
X444531Y332989D03*
X538031Y311800D03*
X622031Y147800D03*
Y256300D03*
G54D74*
X603441Y154660D03*
Y157220D03*
Y159780D03*
Y162340D03*
X619621D03*
Y159780D03*
Y157220D03*
Y154660D03*
G54D75*
X549199Y308657D03*
Y310626D03*
Y312594D03*
Y314563D03*
Y316531D03*
Y318500D03*
Y320469D03*
Y322437D03*
Y324406D03*
Y326374D03*
Y328343D03*
X568485Y310626D03*
Y308657D03*
Y326374D03*
Y324406D03*
Y322437D03*
Y320469D03*
Y318500D03*
Y316531D03*
Y314563D03*
Y312594D03*
Y328343D03*
G54D69*
X477986Y293900D03*
X476016D03*
X474046D03*
X472076D03*
Y303100D03*
X474046D03*
X476016D03*
X477986D03*
G54D68*
X629625Y68661D03*
Y70629D03*
Y72598D03*
Y74566D03*
Y84409D03*
Y86377D03*
Y88346D03*
Y90314D03*
Y92283D03*
Y94251D03*
Y96220D03*
Y98188D03*
Y100157D03*
Y102125D03*
Y104094D03*
Y106063D03*
Y108031D03*
Y110000D03*
Y111968D03*
Y113937D03*
Y115905D03*
Y117874D03*
Y119842D03*
Y121811D03*
Y123779D03*
Y125748D03*
Y127716D03*
Y129685D03*
Y131653D03*
Y133622D03*
Y135590D03*
Y137559D03*
Y139527D03*
Y177323D03*
Y179291D03*
Y181260D03*
Y183228D03*
Y193071D03*
Y195039D03*
Y197008D03*
Y198976D03*
Y200945D03*
Y202913D03*
Y204882D03*
Y206850D03*
Y208819D03*
Y210787D03*
Y212756D03*
Y214725D03*
Y216693D03*
Y218662D03*
Y220630D03*
Y222599D03*
Y224567D03*
Y226536D03*
Y228504D03*
Y230473D03*
Y232441D03*
Y234410D03*
Y236378D03*
Y238347D03*
Y240315D03*
Y242284D03*
Y244252D03*
Y246221D03*
Y248189D03*
X659350Y67677D03*
Y69645D03*
Y71614D03*
Y73582D03*
Y75551D03*
Y85393D03*
Y87362D03*
Y89330D03*
Y91299D03*
Y93267D03*
Y95236D03*
Y97204D03*
Y99173D03*
Y101141D03*
Y103110D03*
Y105078D03*
Y107047D03*
Y109015D03*
Y110984D03*
Y112952D03*
Y114921D03*
Y116889D03*
Y118858D03*
Y120826D03*
Y122795D03*
Y124763D03*
Y126732D03*
Y128700D03*
Y130669D03*
Y132637D03*
Y134606D03*
Y136574D03*
Y138543D03*
Y140511D03*
Y176339D03*
Y178307D03*
Y180276D03*
Y182244D03*
Y184213D03*
Y194055D03*
Y196024D03*
Y197992D03*
Y199961D03*
Y201929D03*
Y203898D03*
Y205866D03*
Y207835D03*
Y209803D03*
Y211772D03*
Y213740D03*
Y215709D03*
Y217677D03*
Y219646D03*
Y221614D03*
Y223583D03*
Y225551D03*
Y227520D03*
Y229488D03*
Y231457D03*
Y233425D03*
Y235394D03*
Y237362D03*
Y239331D03*
Y241299D03*
Y243268D03*
Y245236D03*
Y247205D03*
Y249173D03*
G54D62*
X436031Y303489D03*
X476031Y284300D03*
X473531Y342489D03*
X482531Y286800D03*
X503031Y295300D03*
X576631Y299800D03*
X663031Y163300D03*
G54D78*
X622031Y315100D03*
Y339900D03*
G54D61*
X473231Y310000D03*
G54D58*
X549342Y301700D03*
X667031Y154200D03*
X671031D03*
G54D92*
X549342Y298300D03*
X667031Y150800D03*
X671031D03*
G54D55*
X656299Y63346D03*
Y144842D03*
Y172008D03*
Y253504D03*
G54D91*
X670031Y118200D03*
G54D185*
X286409Y-41818D03*
X246409Y-22629D03*
X248909Y-80818D03*
X239909Y-25129D03*
X219409Y-33629D03*
X145809Y-38129D03*
X59409Y98371D03*
G54D46*
X327008Y-82954D03*
X58409Y235571D03*
X32799Y-82954D03*
G54D213*
X293209Y-67118D03*
X282209Y-44618D03*
X142109Y-42129D03*
X115709Y191071D03*
Y183071D03*
Y187071D03*
Y136071D03*
Y132071D03*
Y119571D03*
Y128071D03*
Y123571D03*
Y82571D03*
Y74571D03*
Y78571D03*
Y19571D03*
Y15071D03*
Y27571D03*
Y23571D03*
Y11071D03*
G54D188*
X245609Y-51929D03*
G54D189*
X277909Y-57618D03*
G54D191*
X291409Y-62418D03*
X179909Y-78229D03*
X153409Y-83229D03*
G54D193*
X249209Y-58929D03*
Y-62929D03*
X51209Y9071D03*
G54D214*
X163598Y-40079D03*
G54D13*
X295909Y-62618D03*
X278409Y-36118D03*
X282659Y-31618D03*
X290409Y-46118D03*
X281409Y-81118D03*
X291409Y-79368D03*
X271909Y-79929D03*
X254409Y-30929D03*
X254909Y-45029D03*
X252909Y-74429D03*
X231496Y-29229D03*
X226909Y-27429D03*
X238909Y-47929D03*
X225909Y-46629D03*
X220909Y-46429D03*
X187098Y-40429D03*
X154598Y-45429D03*
X141909Y-38179D03*
X91409Y97571D03*
X49909Y113171D03*
X50909Y4071D03*
G54D193*
X252609Y-58929D03*
Y-62929D03*
X54609Y9071D03*
G54D179*
X291209Y-73118D03*
X283609D03*
X272709Y-27618D03*
X265109D03*
X272709Y-35618D03*
X265109D03*
X272709Y-43618D03*
X265109D03*
X272709Y-73118D03*
X265109D03*
X94209Y-37929D03*
Y-45929D03*
X86609Y-37929D03*
Y-45929D03*
G54D215*
X52409Y134271D03*
G54D216*
X163598Y-42779D03*
G54D191*
X291409Y-56818D03*
X179909Y-72629D03*
X153409Y-77629D03*
G54D198*
X287409Y-79418D03*
X254409Y-22729D03*
X250409D03*
X234909Y-23729D03*
X230409Y-22229D03*
Y-50229D03*
X234409D03*
X225909D03*
X221909D03*
X181098Y-40229D03*
X149598Y-38229D03*
X53409Y125771D03*
Y118271D03*
G54D165*
X53969Y95821D03*
X51409D03*
X48849D03*
Y89321D03*
X53969D03*
G54D199*
X226309Y-35944D03*
Y-33974D03*
X235509D03*
Y-35944D03*
X226309Y-39884D03*
Y-37914D03*
X235509D03*
Y-39884D03*
G54D196*
X286109Y-36118D03*
X282109Y-40618D03*
X278609Y-86929D03*
X252609Y-66929D03*
X157298Y-41429D03*
X145298Y-45929D03*
X54609Y13071D03*
G54D201*
X142466Y-65929D03*
X117352D03*
G54D198*
X287409Y-82818D03*
X254409Y-26129D03*
X250409D03*
X234909Y-27129D03*
X230409Y-25629D03*
Y-53629D03*
X234409D03*
X225909D03*
X221909D03*
X181098Y-43629D03*
X149598Y-41629D03*
X53409Y122371D03*
Y114871D03*
G54D207*
X141209Y-33929D03*
G54D204*
X242084Y-62018D03*
X239529D03*
X236969D03*
X234409D03*
X231849D03*
X229289D03*
X226734D03*
Y-84218D03*
X229289D03*
X231849D03*
X234409D03*
X236969D03*
X239529D03*
X242084D03*
G54D196*
X282709Y-36118D03*
X278709Y-40618D03*
X275209Y-86929D03*
X249209Y-66929D03*
X153898Y-41429D03*
X141898Y-45929D03*
X51209Y13071D03*
G54D206*
X277909Y-71318D03*
X184409Y-50129D03*
X100409Y113871D03*
Y5371D03*
G54D162*
X210409Y-54129D03*
Y-61729D03*
Y-71129D03*
Y-78729D03*
X202409Y-54129D03*
X194409D03*
X202409Y-61729D03*
X194409D03*
Y-71129D03*
Y-78729D03*
X202409Y-71129D03*
Y-78729D03*
X186409Y-71129D03*
Y-78729D03*
X159909Y-78129D03*
Y-85729D03*
G54D203*
X281844Y-51518D03*
X279879D03*
X277909D03*
Y-63718D03*
X279879D03*
X281844D03*
X275939Y-51518D03*
X273974D03*
Y-63718D03*
X275939D03*
G54D217*
X135609Y-33929D03*
G54D187*
X278609Y-44618D03*
X289609Y-67118D03*
X138509Y-42129D03*
X112109Y191071D03*
Y183071D03*
Y187071D03*
Y136071D03*
Y132071D03*
Y119571D03*
Y128071D03*
Y123571D03*
Y82571D03*
Y74571D03*
Y78571D03*
Y19571D03*
Y15071D03*
Y27571D03*
Y23571D03*
Y11071D03*
G54D218*
X163598Y-60429D03*
G54D206*
X277909Y-74918D03*
X184409Y-53729D03*
X100409Y110271D03*
Y1771D03*
G54D209*
X118999Y103411D03*
Y100851D03*
Y98291D03*
Y95731D03*
X102819D03*
Y98291D03*
Y100851D03*
Y103411D03*
G54D210*
X173241Y-50586D03*
Y-52555D03*
Y-54523D03*
Y-56492D03*
Y-58460D03*
Y-60429D03*
Y-62398D03*
Y-64366D03*
Y-66335D03*
Y-68303D03*
Y-70272D03*
X153955Y-52555D03*
Y-50586D03*
Y-68303D03*
Y-66335D03*
Y-64366D03*
Y-62398D03*
Y-60429D03*
Y-58460D03*
Y-56492D03*
Y-54523D03*
Y-70272D03*
G54D186*
X244454Y-35829D03*
X246424D03*
X248394D03*
X250364D03*
Y-45029D03*
X248394D03*
X246424D03*
X244454D03*
G54D211*
X92815Y189410D03*
Y187442D03*
Y185473D03*
Y183505D03*
Y173662D03*
Y171694D03*
Y169725D03*
Y167757D03*
Y165788D03*
Y163820D03*
Y161851D03*
Y159883D03*
Y157914D03*
Y155946D03*
Y153977D03*
Y152008D03*
Y150040D03*
Y148071D03*
Y146103D03*
Y144134D03*
Y142166D03*
Y140197D03*
Y138229D03*
Y136260D03*
Y134292D03*
Y132323D03*
Y130355D03*
Y128386D03*
Y126418D03*
Y124449D03*
Y122481D03*
Y120512D03*
Y118544D03*
Y80748D03*
Y78780D03*
Y76811D03*
Y74843D03*
Y65000D03*
Y63032D03*
Y61063D03*
Y59095D03*
Y57126D03*
Y55158D03*
Y53189D03*
Y51221D03*
Y49252D03*
Y47284D03*
Y45315D03*
Y43346D03*
Y41378D03*
Y39409D03*
Y37441D03*
Y35472D03*
Y33504D03*
Y31535D03*
Y29567D03*
Y27598D03*
Y25630D03*
Y23661D03*
Y21693D03*
Y19724D03*
Y17756D03*
Y15787D03*
Y13819D03*
Y11850D03*
Y9882D03*
X63090Y190394D03*
Y188426D03*
Y186457D03*
Y184489D03*
Y182520D03*
Y172678D03*
Y170709D03*
Y168741D03*
Y166772D03*
Y164804D03*
Y162835D03*
Y160867D03*
Y158898D03*
Y156930D03*
Y154961D03*
Y152993D03*
Y151024D03*
Y149056D03*
Y147087D03*
Y145119D03*
Y143150D03*
Y141182D03*
Y139213D03*
Y137245D03*
Y135276D03*
Y133308D03*
Y131339D03*
Y129371D03*
Y127402D03*
Y125434D03*
Y123465D03*
Y121497D03*
Y119528D03*
Y117560D03*
Y81732D03*
Y79764D03*
Y77795D03*
Y75827D03*
Y73858D03*
Y64016D03*
Y62047D03*
Y60079D03*
Y58110D03*
Y56142D03*
Y54173D03*
Y52205D03*
Y50236D03*
Y48268D03*
Y46299D03*
Y44331D03*
Y42362D03*
Y40394D03*
Y38425D03*
Y36457D03*
Y34488D03*
Y32520D03*
Y30551D03*
Y28583D03*
Y26614D03*
Y24646D03*
Y22677D03*
Y20709D03*
Y18740D03*
Y16772D03*
Y14803D03*
Y12835D03*
Y10866D03*
Y8898D03*
G54D185*
X286409Y-45418D03*
X246409Y-26229D03*
X248909Y-84418D03*
X239909Y-28729D03*
X219409Y-37229D03*
X145809Y-41729D03*
X59409Y94771D03*
G54D212*
X100409Y-57029D03*
Y-81829D03*
G54D188*
X249209Y-51929D03*
G54D190*
X173098Y-43629D03*
X55409Y103871D03*
X51409D03*
G54D219*
X173098Y-40229D03*
X55409Y107271D03*
X51409D03*
G54D197*
X66141Y194725D03*
Y113229D03*
Y86063D03*
Y4567D03*
G54D220*
X52409Y139871D03*
G54D185*
X659440Y-41818D03*
X619440Y-22629D03*
X621940Y-80818D03*
X612940Y-25129D03*
X592440Y-33629D03*
X518840Y-38129D03*
X432440Y98371D03*
G54D46*
X700039Y-82954D03*
X431440Y235571D03*
X405830Y-82954D03*
G54D213*
X666240Y-67118D03*
X655240Y-44618D03*
X515140Y-42129D03*
X488740Y191071D03*
Y183071D03*
Y187071D03*
Y136071D03*
Y132071D03*
Y119571D03*
Y128071D03*
Y123571D03*
Y82571D03*
Y74571D03*
Y78571D03*
Y19571D03*
Y15071D03*
Y27571D03*
Y23571D03*
Y11071D03*
G54D188*
X618640Y-51929D03*
G54D189*
X650940Y-57618D03*
G54D191*
X664440Y-62418D03*
X552940Y-78229D03*
X526440Y-83229D03*
G54D193*
X622240Y-58929D03*
Y-62929D03*
X424240Y9071D03*
G54D214*
X536629Y-40079D03*
G54D13*
X668940Y-62618D03*
X651440Y-36118D03*
X655690Y-31618D03*
X663440Y-46118D03*
X654440Y-81118D03*
X664440Y-79368D03*
X644940Y-79929D03*
X627440Y-30929D03*
X627940Y-45029D03*
X625940Y-74429D03*
X604527Y-29229D03*
X599940Y-27429D03*
X611940Y-47929D03*
X598940Y-46629D03*
X593940Y-46429D03*
X560129Y-40429D03*
X527629Y-45429D03*
X514940Y-38179D03*
X464440Y97571D03*
X422940Y113171D03*
X423940Y4071D03*
G54D193*
X625640Y-58929D03*
Y-62929D03*
X427640Y9071D03*
G54D179*
X664240Y-73118D03*
X656640D03*
X645740Y-27618D03*
X638140D03*
X645740Y-35618D03*
X638140D03*
X645740Y-43618D03*
X638140D03*
X645740Y-73118D03*
X638140D03*
X467240Y-37929D03*
Y-45929D03*
X459640Y-37929D03*
Y-45929D03*
G54D215*
X425440Y134271D03*
G54D216*
X536629Y-42779D03*
G54D191*
X664440Y-56818D03*
X552940Y-72629D03*
X526440Y-77629D03*
G54D198*
X660440Y-79418D03*
X627440Y-22729D03*
X623440D03*
X607940Y-23729D03*
X603440Y-22229D03*
Y-50229D03*
X607440D03*
X598940D03*
X594940D03*
X554129Y-40229D03*
X522629Y-38229D03*
X426440Y125771D03*
Y118271D03*
G54D165*
X427000Y95821D03*
X424440D03*
X421880D03*
Y89321D03*
X427000D03*
G54D199*
X599340Y-35944D03*
Y-33974D03*
X608540D03*
Y-35944D03*
X599340Y-39884D03*
Y-37914D03*
X608540D03*
Y-39884D03*
G54D196*
X659140Y-36118D03*
X655140Y-40618D03*
X651640Y-86929D03*
X625640Y-66929D03*
X530329Y-41429D03*
X518329Y-45929D03*
X427640Y13071D03*
G54D201*
X515497Y-65929D03*
X490383D03*
G54D198*
X660440Y-82818D03*
X627440Y-26129D03*
X623440D03*
X607940Y-27129D03*
X603440Y-25629D03*
Y-53629D03*
X607440D03*
X598940D03*
X594940D03*
X554129Y-43629D03*
X522629Y-41629D03*
X426440Y122371D03*
Y114871D03*
G54D207*
X514240Y-33929D03*
G54D204*
X615115Y-62018D03*
X612560D03*
X610000D03*
X607440D03*
X604880D03*
X602320D03*
X599765D03*
Y-84218D03*
X602320D03*
X604880D03*
X607440D03*
X610000D03*
X612560D03*
X615115D03*
G54D196*
X655740Y-36118D03*
X651740Y-40618D03*
X648240Y-86929D03*
X622240Y-66929D03*
X526929Y-41429D03*
X514929Y-45929D03*
X424240Y13071D03*
G54D206*
X650940Y-71318D03*
X557440Y-50129D03*
X473440Y113871D03*
Y5371D03*
G54D162*
X583440Y-54129D03*
Y-61729D03*
Y-71129D03*
Y-78729D03*
X575440Y-54129D03*
X567440D03*
X575440Y-61729D03*
X567440D03*
Y-71129D03*
Y-78729D03*
X575440Y-71129D03*
Y-78729D03*
X559440Y-71129D03*
Y-78729D03*
X532940Y-78129D03*
Y-85729D03*
G54D203*
X654875Y-51518D03*
X652910D03*
X650940D03*
Y-63718D03*
X652910D03*
X654875D03*
X648970Y-51518D03*
X647005D03*
Y-63718D03*
X648970D03*
G54D217*
X508640Y-33929D03*
G54D187*
X651640Y-44618D03*
X662640Y-67118D03*
X511540Y-42129D03*
X485140Y191071D03*
Y183071D03*
Y187071D03*
Y136071D03*
Y132071D03*
Y119571D03*
Y128071D03*
Y123571D03*
Y82571D03*
Y74571D03*
Y78571D03*
Y19571D03*
Y15071D03*
Y27571D03*
Y23571D03*
Y11071D03*
G54D218*
X536629Y-60429D03*
G54D206*
X650940Y-74918D03*
X557440Y-53729D03*
X473440Y110271D03*
Y1771D03*
G54D209*
X492030Y103411D03*
Y100851D03*
Y98291D03*
Y95731D03*
X475850D03*
Y98291D03*
Y100851D03*
Y103411D03*
G54D210*
X546272Y-50586D03*
Y-52555D03*
Y-54523D03*
Y-56492D03*
Y-58460D03*
Y-60429D03*
Y-62398D03*
Y-64366D03*
Y-66335D03*
Y-68303D03*
Y-70272D03*
X526986Y-52555D03*
Y-50586D03*
Y-68303D03*
Y-66335D03*
Y-64366D03*
Y-62398D03*
Y-60429D03*
Y-58460D03*
Y-56492D03*
Y-54523D03*
Y-70272D03*
G54D186*
X617485Y-35829D03*
X619455D03*
X621425D03*
X623395D03*
Y-45029D03*
X621425D03*
X619455D03*
X617485D03*
G54D211*
X465846Y189410D03*
Y187442D03*
Y185473D03*
Y183505D03*
Y173662D03*
Y171694D03*
Y169725D03*
Y167757D03*
Y165788D03*
Y163820D03*
Y161851D03*
Y159883D03*
Y157914D03*
Y155946D03*
Y153977D03*
Y152008D03*
Y150040D03*
Y148071D03*
Y146103D03*
Y144134D03*
Y142166D03*
Y140197D03*
Y138229D03*
Y136260D03*
Y134292D03*
Y132323D03*
Y130355D03*
Y128386D03*
Y126418D03*
Y124449D03*
Y122481D03*
Y120512D03*
Y118544D03*
Y80748D03*
Y78780D03*
Y76811D03*
Y74843D03*
Y65000D03*
Y63032D03*
Y61063D03*
Y59095D03*
Y57126D03*
Y55158D03*
Y53189D03*
Y51221D03*
Y49252D03*
Y47284D03*
Y45315D03*
Y43346D03*
Y41378D03*
Y39409D03*
Y37441D03*
Y35472D03*
Y33504D03*
Y31535D03*
Y29567D03*
Y27598D03*
Y25630D03*
Y23661D03*
Y21693D03*
Y19724D03*
Y17756D03*
Y15787D03*
Y13819D03*
Y11850D03*
Y9882D03*
X436121Y190394D03*
Y188426D03*
Y186457D03*
Y184489D03*
Y182520D03*
Y172678D03*
Y170709D03*
Y168741D03*
Y166772D03*
Y164804D03*
Y162835D03*
Y160867D03*
Y158898D03*
Y156930D03*
Y154961D03*
Y152993D03*
Y151024D03*
Y149056D03*
Y147087D03*
Y145119D03*
Y143150D03*
Y141182D03*
Y139213D03*
Y137245D03*
Y135276D03*
Y133308D03*
Y131339D03*
Y129371D03*
Y127402D03*
Y125434D03*
Y123465D03*
Y121497D03*
Y119528D03*
Y117560D03*
Y81732D03*
Y79764D03*
Y77795D03*
Y75827D03*
Y73858D03*
Y64016D03*
Y62047D03*
Y60079D03*
Y58110D03*
Y56142D03*
Y54173D03*
Y52205D03*
Y50236D03*
Y48268D03*
Y46299D03*
Y44331D03*
Y42362D03*
Y40394D03*
Y38425D03*
Y36457D03*
Y34488D03*
Y32520D03*
Y30551D03*
Y28583D03*
Y26614D03*
Y24646D03*
Y22677D03*
Y20709D03*
Y18740D03*
Y16772D03*
Y14803D03*
Y12835D03*
Y10866D03*
Y8898D03*
G54D185*
X659440Y-45418D03*
X619440Y-26229D03*
X621940Y-84418D03*
X612940Y-28729D03*
X592440Y-37229D03*
X518840Y-41729D03*
X432440Y94771D03*
G54D212*
X473440Y-57029D03*
Y-81829D03*
G54D188*
X622240Y-51929D03*
G54D190*
X546129Y-43629D03*
X428440Y103871D03*
X424440D03*
G54D219*
X546129Y-40229D03*
X428440Y107271D03*
X424440D03*
G54D197*
X439172Y194725D03*
Y113229D03*
Y86063D03*
Y4567D03*
G54D220*
X425440Y139871D03*
G54D40*
X-176139Y-183003D02*
G75*
G03X-176139Y-183003I-12000D01*
X-181289D02*
G03X-181289Y-183003I-6850D01*
X-172139D02*
G01X-204139D01*
X-188139Y-199003D02*
G01Y-167003D01*
X-172139Y-199003D02*
G01Y-279003D01*
Y-279003D02*
G01X1178561D01*
X-172139Y-234503D02*
G01X1178561D01*
X-172139Y-199003D02*
G01X1178561D01*
X391061D02*
G01Y-279003D01*
X528561Y-199003D02*
G01Y-279003D01*
X643561Y-199003D02*
G01Y-279003D01*
X811061Y-199003D02*
G01Y-279003D01*
X981061Y-199003D02*
G01Y-279003D01*
X1178561Y-199003D02*
G01Y-279003D01*
X1210561Y-183003D02*
G01X1178561D01*
X1206561D02*
G03X1206561Y-183003I-12000D01*
X1201411D02*
G03X1201411Y-183003I-6850D01*
X1194561Y-199003D02*
G01Y-167003D01*
G54D41*
X-148956Y-251503D02*
G01Y-269003D01*
X-140222*
X-127089Y-257337D02*
G01Y-269003D01*
Y-252670D02*
G01X-127526Y-252378D01*
Y-251795*
X-127089Y-251503*
X-126652Y-251795*
Y-252378*
X-127089Y-252670*
X-112646Y-273378D02*
G01X-111117Y-274545D01*
X-109371Y-274836*
X-107843Y-274545*
X-106532Y-273087*
X-105659Y-271045*
Y-257337*
Y-259670D02*
G01X-106532Y-258503D01*
X-107843Y-257628*
X-109371Y-257337*
X-111117Y-257920*
X-112209Y-259086*
X-113083Y-261128*
X-113519Y-263170*
X-113301Y-264920*
X-112427Y-266962*
X-111117Y-268420*
X-109371Y-269003*
X-108061Y-268711*
X-106532Y-267545*
X-105659Y-266379*
X-95801Y-269003D02*
G01Y-251503D01*
Y-259961D02*
G01X-94709Y-258503D01*
X-93617Y-257628*
X-91871Y-257337*
X-90561Y-257628*
X-89032Y-258795*
X-88377Y-260545*
Y-269003*
X-74589Y-251503D02*
G01Y-269003D01*
X-77646Y-257337D02*
G01X-71532D01*
X-60801Y-269003D02*
G01Y-257337D01*
Y-260253D02*
G01X-59927Y-258795D01*
X-58617Y-257628*
X-56871Y-257337*
X-55343Y-257628*
X-54032Y-258795*
X-53377Y-260836*
Y-269003*
X-39589Y-257337D02*
G01Y-269003D01*
Y-252670D02*
G01X-40026Y-252378D01*
Y-251795*
X-39589Y-251503*
X-39152Y-251795*
Y-252378*
X-39589Y-252670*
X-25801Y-269003D02*
G01Y-257337D01*
Y-260253D02*
G01X-24927Y-258795D01*
X-23617Y-257628*
X-21871Y-257337*
X-20343Y-257628*
X-19032Y-258795*
X-18377Y-260836*
Y-269003*
X-7646Y-273378D02*
G01X-6117Y-274545D01*
X-4371Y-274836*
X-2843Y-274545*
X-1532Y-273087*
X-659Y-271045*
Y-257337*
Y-259670D02*
G01X-1532Y-258503D01*
X-2843Y-257628*
X-4371Y-257337*
X-6117Y-257920*
X-7209Y-259086*
X-8083Y-261128*
X-8519Y-263170*
X-8301Y-264920*
X-7427Y-266962*
X-6117Y-268420*
X-4371Y-269003*
X-3061Y-268711*
X-1532Y-267545*
X-659Y-266379*
X26044Y-269003D02*
G01Y-251503D01*
X31284*
X33031Y-252378*
X34341Y-254420*
X34778Y-256753*
X34341Y-259086*
X33249Y-260836*
X31284Y-261712*
X26044*
X42452Y-251503D02*
G01X47911Y-269003D01*
X53370Y-251503*
X65411D02*
G01Y-269003D01*
X60389Y-251503D02*
G01X70433D01*
X94734Y-269003D02*
G01Y-251503D01*
X100411Y-266086*
X106088Y-251503*
Y-269003*
X117911Y-269586D02*
G01X117474Y-269295D01*
Y-268711*
X117911Y-268420*
X118348Y-268711*
Y-269295*
X117911Y-269586*
X131263Y-254420D02*
G01X132573Y-252670D01*
X134101Y-251795*
X135848Y-251503*
X138031Y-252086*
X139559Y-253545*
X139996Y-255294*
X139778Y-257045*
X138904Y-258503*
X134538Y-261420*
X132573Y-263461*
X131263Y-266379*
X130826Y-269003*
X139996*
X164952D02*
G01X170411Y-251503D01*
X175870Y-269003*
X173904Y-262878D02*
G01X166917D01*
X191841Y-251503D02*
G01Y-269003D01*
Y-266379D02*
G01X190968Y-267837D01*
X189657Y-268711*
X188129Y-269003*
X186383Y-268420*
X185073Y-266962*
X184199Y-265212*
X183981Y-263170*
X184199Y-261128*
X185073Y-259378*
X186383Y-257920*
X188129Y-257337*
X189657Y-257628*
X190749Y-258212*
X191841Y-259378*
X209341Y-269003D02*
G01Y-257337D01*
Y-259378D02*
G01X208468Y-258212D01*
X207157Y-257628*
X205629Y-257337*
X204101Y-257920*
X202791Y-259086*
X201917Y-260836*
X201481Y-263170*
X201917Y-265503*
X202791Y-267253*
X204101Y-268420*
X205629Y-269003*
X207157Y-268711*
X208468Y-267837*
X209341Y-266670*
X218981Y-274836D02*
G01Y-257337D01*
Y-259961D02*
G01X220073Y-258503D01*
X221164Y-257628*
X222911Y-257337*
X224439Y-257628*
X225968Y-259086*
X226623Y-261128*
X226841Y-263170*
X226623Y-265212*
X225968Y-267253*
X224657Y-268420*
X222911Y-269003*
X221383Y-268711*
X219854Y-267837*
X218981Y-266670*
X240411Y-251503D02*
G01Y-269003D01*
X237354Y-257337D02*
G01X243468D01*
X257911Y-269003D02*
G01X256601Y-268711D01*
X255291Y-267545*
X254417Y-265503*
X253981Y-263170*
X254417Y-260836*
X255291Y-258795*
X256601Y-257628*
X257911Y-257337*
X259221Y-257628*
X260531Y-258795*
X261404Y-260836*
X261623Y-263170*
X261404Y-265503*
X260531Y-267545*
X259221Y-268711*
X257911Y-269003*
X272354D02*
G01Y-257337D01*
Y-259670D02*
G01X273446Y-258503D01*
X274538Y-257628*
X276066Y-257337*
X277157Y-257628*
X278468Y-258503*
X315214Y-252962D02*
G01X313904Y-252086D01*
X312376Y-251503*
X310629*
X308664Y-252378*
X307136Y-253836*
X306044Y-255587*
X305171Y-258503*
X304952Y-261128*
X305389Y-263753*
X306044Y-265503*
X307354Y-267253*
X308883Y-268420*
X310411Y-269003*
X311939*
X313468Y-268420*
X314778Y-267545*
X315870Y-266379*
X331841Y-269003D02*
G01Y-257337D01*
Y-259378D02*
G01X330968Y-258212D01*
X329657Y-257628*
X328129Y-257337*
X326601Y-257920*
X325291Y-259086*
X324417Y-260836*
X323981Y-263170*
X324417Y-265503*
X325291Y-267253*
X326601Y-268420*
X328129Y-269003*
X329657Y-268711*
X330968Y-267837*
X331841Y-266670*
X342354Y-269003D02*
G01Y-257337D01*
Y-259670D02*
G01X343446Y-258503D01*
X344538Y-257628*
X346066Y-257337*
X347157Y-257628*
X348468Y-258503*
X366841Y-251503D02*
G01Y-269003D01*
Y-266379D02*
G01X365968Y-267837D01*
X364657Y-268711*
X363129Y-269003*
X361383Y-268420*
X360073Y-266962*
X359199Y-265212*
X358981Y-263170*
X359199Y-261128*
X360073Y-259378*
X361383Y-257920*
X363129Y-257337*
X364657Y-257628*
X365749Y-258212*
X366841Y-259378*
X-1Y-113228D02*
G01Y-117165D01*
Y-117165D02*
G03X7873Y-125039I7874D01*
Y-125039D02*
G01X714566D01*
Y-125039D02*
G03X722440Y-117165J7874D01*
Y-117165D02*
G01Y-113228D01*
X1968Y40473D02*
G01X9842D01*
X11811Y38504D02*
G03X9842Y40473I-1969D01*
X11811Y38504D02*
G01Y-16772D01*
X9842Y-18740D02*
G03X11811Y-16772J1969D01*
X9842Y-18740D02*
G01X1968D01*
Y-18740D02*
G03X0Y-20709J-1968D01*
Y-20709D02*
G01Y-97480D01*
Y-97480D02*
G03X7874Y-105354I7874D01*
Y-105354D02*
G01X341535D01*
Y-105354D02*
G03X349409Y-97480J7874D01*
Y-97480D02*
G01Y-15748D01*
Y-15748D02*
G03X341535Y-7874I-7874D01*
Y-7874D02*
G01X141338D01*
X133464Y0D02*
G03X141338Y-7874I7874D01*
X133464Y0D02*
G01Y250197D01*
Y250197D02*
G03X125590Y258071I-7874D01*
Y258071D02*
G01X1968D01*
Y258071D02*
G03X0Y256102J-1968D01*
Y256102D02*
G01Y236673D01*
Y236673D02*
G03X1968Y234705I1968D01*
Y234705D02*
G01X28346D01*
X30315Y232736D02*
G03X28346Y234705I-1969D01*
X30315Y232736D02*
G01Y216004D01*
X28346Y214036D02*
G03X30315Y216004I1J1968D01*
X28346Y214036D02*
G01X23228D01*
Y214036D02*
G03X21259Y212067J-1969D01*
Y212067D02*
G01Y86752D01*
Y86752D02*
G03X23228Y84784I1969J1D01*
Y84784D02*
G01X28346D01*
X30315Y82815D02*
G03X28346Y84784I-1969D01*
X30315Y82815D02*
G01Y66083D01*
X28346Y64114D02*
G03X30315Y66083J1969D01*
X28346Y64114D02*
G01X1968D01*
Y64114D02*
G03X0Y62146J-1968D01*
Y62146D02*
G01Y42441D01*
Y42441D02*
G03X1968Y40473I1968D01*
X-1Y-113228D02*
G01X13591D01*
X347441Y217598D02*
G01X339567D01*
X337598Y219567D02*
G03X339567Y217598I1969D01*
X337598Y219567D02*
G01Y274843D01*
X339567Y276811D02*
G03X337598Y274843J-1969D01*
X339567Y276811D02*
G01X347441D01*
Y276811D02*
G03X349409Y278780J1968D01*
Y278780D02*
G01Y355551D01*
Y355551D02*
G03X341535Y363425I-7874D01*
Y363425D02*
G01X7874D01*
Y363425D02*
G03X0Y355551J-7874D01*
Y355551D02*
G01Y273819D01*
Y273819D02*
G03X7874Y265945I7874D01*
Y265945D02*
G01X208071D01*
X215945Y258071D02*
G03X208071Y265945I-7874D01*
X215945Y258071D02*
G01Y7874D01*
Y7874D02*
G03X223819Y0I7874D01*
Y0D02*
G01X347441D01*
Y0D02*
G03X349409Y1969J1968D01*
Y1969D02*
G01Y21398D01*
Y21398D02*
G03X347441Y23366I-1968D01*
Y23366D02*
G01X321063D01*
X319094Y25335D02*
G03X321063Y23366I1969D01*
X319094Y25335D02*
G01Y42067D01*
X321063Y44035D02*
G03X319094Y42067J-1969D01*
X321063Y44035D02*
G01X326181D01*
Y44035D02*
G03X328150Y46004J1969D01*
Y46004D02*
G01Y171319D01*
Y171319D02*
G03X326181Y173287I-1968D01*
Y173287D02*
G01X321063D01*
X319094Y175256D02*
G03X321063Y173287I1969D01*
X319094Y175256D02*
G01Y191988D01*
X321063Y193957D02*
G03X319094Y191988J-1969D01*
X321063Y193957D02*
G01X347441D01*
Y193957D02*
G03X349409Y195925J1968D01*
Y195925D02*
G01Y215630D01*
Y215630D02*
G03X347441Y217598I-1968D01*
X245745Y383110D02*
G01X7874D01*
Y383110D02*
G03X0Y375236J-7874D01*
Y375236D02*
G01Y371299D01*
Y371299D02*
G01X13591D01*
Y-113228D02*
G03X13591Y-105354J3937D01*
Y258071D02*
G03X13591Y265945J3937D01*
Y363425D02*
G03X13591Y371299J3937D01*
X38787Y-113228D02*
G01X237000D01*
X38787Y-105354D02*
G03X38787Y-113228I1J-3937D01*
Y265945D02*
G03X38787Y258071I1J-3937D01*
X237000Y371299D02*
G01X38787D01*
Y371299D02*
G03X38787Y363425I1J-3937D01*
X68484Y-224003D02*
G01Y-206503D01*
X74161Y-221086*
X79838Y-206503*
Y-224003*
X91661D02*
G01X90351Y-223711D01*
X89041Y-222545*
X88167Y-220503*
X87731Y-218170*
X88167Y-215836*
X89041Y-213795*
X90351Y-212628*
X91661Y-212337*
X92971Y-212628*
X94281Y-213795*
X95154Y-215836*
X95373Y-218170*
X95154Y-220503*
X94281Y-222545*
X92971Y-223711*
X91661Y-224003*
X113091Y-206503D02*
G01Y-224003D01*
Y-221379D02*
G01X112218Y-222837D01*
X110907Y-223711*
X109379Y-224003*
X107633Y-223420*
X106323Y-221962*
X105449Y-220212*
X105231Y-218170*
X105449Y-216128*
X106323Y-214378*
X107633Y-212920*
X109379Y-212337*
X110907Y-212628*
X111999Y-213212*
X113091Y-214378*
X123386Y-216128D02*
G01X130373D01*
X129718Y-214086*
X128626Y-212920*
X127098Y-212337*
X125569Y-212628*
X124259Y-213503*
X123386Y-215545*
X122949Y-217295*
Y-219045*
X123386Y-220795*
X124478Y-222545*
X125788Y-223711*
X127316Y-224003*
X128844Y-223420*
X130373Y-221670*
X144161Y-224003D02*
G01Y-206503D01*
X141338Y116437D02*
G03X133464Y116437I-3937D01*
Y141634D02*
G03X141338Y141634I3937D01*
Y0D02*
G01Y116437D01*
X162106Y0D02*
G01X141337D01*
X141338Y141634D02*
G01Y258071D01*
Y258071D02*
G01X162106D01*
Y-7874D02*
G03X162106Y0J3937D01*
X179626Y62719D02*
G03X171044Y62719I-4291D01*
Y62719D02*
G03X179626Y62719I4291D01*
Y189063D02*
G03X171044Y189062I-4291D01*
Y189062D02*
G03X179626Y189063I4291J1D01*
X162106Y258071D02*
G03X162106Y265945J3937D01*
X187302Y0D02*
G03X187302Y-7874I1J-3937D01*
X208071Y0D02*
G01X187302D01*
Y265945D02*
G03X187302Y258071I1J-3937D01*
Y258071D02*
G01X208071D01*
X207913Y0D02*
G01X208071D01*
Y116437D02*
G01Y0D01*
X215945Y116437D02*
G03X208071Y116437I-3937D01*
Y141634D02*
G03X215945Y141634I3937D01*
X208071Y258071D02*
G01Y141634D01*
X237000Y-113228D02*
G03X237000Y-105354J3937D01*
Y363425D02*
G03X237000Y371299J3937D01*
X245745Y383110D02*
G03X253619Y383110I3937D01*
X722440Y371299D02*
G01Y375236D01*
Y375236D02*
G03X714566Y383110I-7874D01*
Y383110D02*
G01X253619D01*
X262196Y-113228D02*
G01X460244D01*
X262196Y-105354D02*
G03X262196Y-113228J-3937D01*
Y371299D02*
G01X460244D01*
X262196D02*
G03X262196Y363425J-3937D01*
X310621Y-7874D02*
G03X310621Y0J3937D01*
X335817D02*
G03X335817Y-7874I1J-3937D01*
X353346Y-47481D02*
G03X349409Y-51418J-3937D01*
Y-20709D02*
G03X353346Y-24646I3937D01*
Y282717D02*
G03X349409Y278780J-3937D01*
Y309489D02*
G03X353346Y305552I3937D01*
Y-47481D02*
G01X369094D01*
X373031Y-51418D02*
G03X369094Y-47481I-3937D01*
X353346Y-24646D02*
G01X369094D01*
Y-24646D02*
G03X373031Y-20709J3937D01*
X353346Y282717D02*
G01X369094D01*
X373031Y278780D02*
G03X369094Y282717I-3937D01*
X353346Y305552D02*
G01X369094D01*
Y305552D02*
G03X373031Y309489J3937D01*
X374999Y40473D02*
G01X382873D01*
X384842Y38504D02*
G03X382873Y40473I-1969D01*
X384842Y38504D02*
G01Y-16772D01*
X382873Y-18740D02*
G03X384842Y-16772J1969D01*
X382873Y-18740D02*
G01X374999D01*
Y-18740D02*
G03X373031Y-20709J-1968D01*
Y-20709D02*
G01Y-97480D01*
Y-97480D02*
G03X380905Y-105354I7874D01*
Y-105354D02*
G01X714566D01*
Y-105354D02*
G03X722440Y-97480J7874D01*
Y-97480D02*
G01Y-15748D01*
Y-15748D02*
G03X714566Y-7874I-7874D01*
Y-7874D02*
G01X514369D01*
X506495Y0D02*
G03X514369Y-7874I7874D01*
X506495Y0D02*
G01Y250197D01*
Y250197D02*
G03X498621Y258071I-7874D01*
Y258071D02*
G01X374999D01*
Y258071D02*
G03X373031Y256102J-1968D01*
Y256102D02*
G01Y236673D01*
Y236673D02*
G03X374999Y234705I1968D01*
Y234705D02*
G01X401377D01*
X403346Y232736D02*
G03X401377Y234705I-1969D01*
X403346Y232736D02*
G01Y216004D01*
X401377Y214036D02*
G03X403346Y216004I1J1968D01*
X401377Y214036D02*
G01X396259D01*
Y214036D02*
G03X394290Y212067J-1969D01*
Y212067D02*
G01Y86752D01*
Y86752D02*
G03X396259Y84784I1969J1D01*
Y84784D02*
G01X401377D01*
X403346Y82815D02*
G03X401377Y84784I-1969D01*
X403346Y82815D02*
G01Y66083D01*
X401377Y64114D02*
G03X403346Y66083J1969D01*
X401377Y64114D02*
G01X374999D01*
Y64114D02*
G03X373031Y62146J-1968D01*
Y62146D02*
G01Y42441D01*
Y42441D02*
G03X374999Y40473I1968D01*
X720472Y217598D02*
G01X712598D01*
X710629Y219567D02*
G03X712598Y217598I1969D01*
X710629Y219567D02*
G01Y274843D01*
X712598Y276811D02*
G03X710629Y274843J-1969D01*
X712598Y276811D02*
G01X720472D01*
Y276811D02*
G03X722440Y278780J1968D01*
Y278780D02*
G01Y355551D01*
Y355551D02*
G03X714566Y363425I-7874D01*
Y363425D02*
G01X380905D01*
Y363425D02*
G03X373031Y355551J-7874D01*
Y355551D02*
G01Y273819D01*
Y273819D02*
G03X380905Y265945I7874D01*
Y265945D02*
G01X581102D01*
X588976Y258071D02*
G03X581102Y265945I-7874D01*
X588976Y258071D02*
G01Y7874D01*
Y7874D02*
G03X596850Y0I7874D01*
Y0D02*
G01X720472D01*
Y0D02*
G03X722440Y1969J1968D01*
Y1969D02*
G01Y21398D01*
Y21398D02*
G03X720472Y23366I-1968D01*
Y23366D02*
G01X694094D01*
X692125Y25335D02*
G03X694094Y23366I1969D01*
X692125Y25335D02*
G01Y42067D01*
X694094Y44035D02*
G03X692125Y42067J-1969D01*
X694094Y44035D02*
G01X699212D01*
Y44035D02*
G03X701181Y46004J1969D01*
Y46004D02*
G01Y171319D01*
Y171319D02*
G03X699212Y173287I-1969J-1D01*
Y173287D02*
G01X694094D01*
X692125Y175256D02*
G03X694094Y173287I1969D01*
X692125Y175256D02*
G01Y191988D01*
X694094Y193957D02*
G03X692125Y191988J-1969D01*
X694094Y193957D02*
G01X720472D01*
Y193957D02*
G03X722440Y195925J1968D01*
Y195925D02*
G01Y215630D01*
Y215630D02*
G03X720472Y217598I-1968D01*
X386622Y258071D02*
G03X386622Y265945J3937D01*
X424761Y-269003D02*
G01Y-251503D01*
X422141Y-255003*
Y-269003D02*
G01X427381D01*
X437458Y-266379D02*
G01X438767Y-267837D01*
X440296Y-268711*
X442261Y-269003*
X444226Y-268420*
X445754Y-267253*
X446846Y-265212*
X447064Y-262878*
X446628Y-260545*
X445536Y-259086*
X444007Y-257920*
X442479Y-257628*
X440951Y-257920*
X438986Y-259086*
X439641Y-251503*
X445536*
X459324Y-269003D02*
G01X459761Y-265212D01*
X460416Y-262003*
X461289Y-259086*
X462381Y-255878*
X464128Y-251503*
X455394*
X472458Y-266379D02*
G01X473767Y-267837D01*
X475296Y-268711*
X477261Y-269003*
X479226Y-268420*
X480754Y-267253*
X481846Y-265212*
X482064Y-262878*
X481628Y-260545*
X480536Y-259086*
X479007Y-257920*
X477479Y-257628*
X475951Y-257920*
X473986Y-259086*
X474641Y-251503*
X480536*
X494761D02*
G01X493014Y-252086D01*
X491704Y-253545*
X490831Y-255294*
X490176Y-257628*
X489958Y-260253*
X490176Y-262878*
X490831Y-265212*
X491704Y-266962*
X493014Y-268420*
X494761Y-269003*
X496507Y-268420*
X497818Y-266962*
X498691Y-265212*
X499346Y-262878*
X499564Y-260253*
X499346Y-257628*
X498691Y-255294*
X497818Y-253545*
X496507Y-252086*
X494761Y-251503*
X411644Y-224003D02*
G01Y-206503D01*
X416884*
X418631Y-207378*
X419941Y-209420*
X420378Y-211753*
X419941Y-214086*
X418849Y-215836*
X416884Y-216712*
X411644*
X438314Y-207962D02*
G01X437004Y-207086D01*
X435476Y-206503*
X433729*
X431764Y-207378*
X430236Y-208836*
X429144Y-210587*
X428271Y-213503*
X428052Y-216128*
X428489Y-218753*
X429144Y-220503*
X430454Y-222253*
X431983Y-223420*
X433511Y-224003*
X435039*
X436568Y-223420*
X437878Y-222545*
X438970Y-221379*
X452757Y-214670D02*
G01X453631Y-213795D01*
X454286Y-212337*
X454723Y-210294*
X454286Y-208545*
X453413Y-207378*
X451884Y-206503*
X445989*
Y-224003*
X453194*
X454723Y-222837*
X455596Y-221086*
X456033Y-219045*
X455596Y-217003*
X454286Y-215253*
X452757Y-214670*
X445989*
X461961Y-229836D02*
G01X475061D01*
X480989Y-224003D02*
G01Y-206503D01*
X491033Y-224003*
Y-206503*
X503511Y-224003D02*
G01X501764Y-223711D01*
X500236Y-222545*
X498926Y-220795*
X498052Y-218753*
X497616Y-216420*
Y-214086*
X498052Y-211753*
X498926Y-209711*
X500236Y-207962*
X501764Y-206795*
X503511Y-206503*
X505257Y-206795*
X506786Y-207962*
X508096Y-209711*
X508970Y-211753*
X509406Y-214086*
Y-216420*
X508970Y-218753*
X508096Y-220795*
X506786Y-222545*
X505257Y-223711*
X503511Y-224003*
X411819Y265945D02*
G03X411819Y258071J-3937D01*
X460244Y-113228D02*
G03X460244Y-105354J3937D01*
Y363425D02*
G03X460244Y371299J3937D01*
X485441Y-105354D02*
G03X485441Y-113228J-3937D01*
Y371299D02*
G03X485441Y363425J-3937D01*
Y-113228D02*
G01X683652D01*
X485441Y371299D02*
G01X683652D01*
X514369Y0D02*
G01Y116437D01*
X535137Y0D02*
G01X514369D01*
Y116437D02*
G03X506494Y116437I-3937D01*
Y141634D02*
G03X514369Y141634I3938D01*
Y141634D02*
G01Y258071D01*
Y258071D02*
G01X535137D01*
Y-7874D02*
G03X535137Y0J3937D01*
X551396Y69008D02*
G03X542813Y69008I-4291D01*
Y69008D02*
G03X551396Y69008I4292D01*
Y195351D02*
G03X542813Y195352I-4292D01*
Y195352D02*
G03X551396Y195351I4291J-1D01*
X535137Y258071D02*
G03X535137Y265945J3937D01*
X554352Y-206503D02*
G01X559811Y-224003D01*
X565270Y-206503*
X581678Y-224003D02*
G01X572944D01*
Y-206503*
X581678*
X578184Y-214961D02*
G01X572944D01*
X590444Y-224003D02*
G01Y-206503D01*
X595903*
X597649Y-207378*
X598741Y-208545*
X599178Y-210878*
X598741Y-213212*
X597431Y-214670*
X595903Y-215545*
X590444*
X595903D02*
G01X599178Y-224003D01*
X612311Y-224586D02*
G01X611874Y-224295D01*
Y-223711*
X612311Y-223420*
X612748Y-223711*
Y-224295*
X612311Y-224586*
X560333Y0D02*
G03X560333Y-7874I1J-3937D01*
X581102Y0D02*
G01X560333D01*
Y265945D02*
G03X560333Y258071I1J-3937D01*
Y258071D02*
G01X581102D01*
X586061Y-269003D02*
G01Y-251503D01*
X583441Y-255003*
Y-269003D02*
G01X588681D01*
X581102Y116437D02*
G01Y0D01*
X588976Y116437D02*
G03X581102Y116437I-3937D01*
Y141634D02*
G03X588976Y141634I3937D01*
X581102Y258071D02*
G01Y141634D01*
X701011Y-251503D02*
G01Y-269003D01*
X695989Y-251503D02*
G01X706033D01*
X713926Y-266670D02*
G01X715673Y-268128D01*
X717638Y-269003*
X719384*
X721131Y-268128*
X722441Y-266670*
X723096Y-264628*
X722659Y-262587*
X721568Y-260836*
X719603Y-259670*
X716983Y-259086*
X715454Y-257920*
X714799Y-255878*
X715236Y-253836*
X716328Y-252378*
X717856Y-251503*
X719384*
X720913Y-252086*
X722223Y-253545*
X730334Y-269003D02*
G01Y-251503D01*
X736011Y-266086*
X741688Y-251503*
Y-269003*
X748708D02*
G01Y-251503D01*
X753074*
X754821Y-252378*
X756131Y-253545*
X757223Y-255294*
X758096Y-257337*
X758314Y-260253*
X758096Y-263170*
X757223Y-265212*
X756131Y-266962*
X754821Y-268128*
X753074Y-269003*
X748708*
X687894Y-206503D02*
G01Y-224003D01*
X696628*
X713691D02*
G01Y-212337D01*
Y-214378D02*
G01X712818Y-213212D01*
X711507Y-212628*
X709979Y-212337*
X708451Y-212920*
X707141Y-214086*
X706267Y-215836*
X705831Y-218170*
X706267Y-220503*
X707141Y-222253*
X708451Y-223420*
X709979Y-224003*
X711507Y-223711*
X712818Y-222837*
X713691Y-221670*
X722676Y-229253D02*
G01X723986Y-229836D01*
X725733Y-229253*
X726824Y-228087*
X727698Y-226628*
X729007Y-221962*
X731846Y-212337*
X724859D02*
G01X729007Y-221962D01*
X741486Y-216128D02*
G01X748473D01*
X747818Y-214086*
X746726Y-212920*
X745198Y-212337*
X743669Y-212628*
X742359Y-213503*
X741486Y-215545*
X741049Y-217295*
Y-219045*
X741486Y-220795*
X742578Y-222545*
X743888Y-223711*
X745416Y-224003*
X746944Y-223420*
X748473Y-221670*
X759204Y-224003D02*
G01Y-212337D01*
Y-214670D02*
G01X760296Y-213503D01*
X761388Y-212628*
X762916Y-212337*
X764007Y-212628*
X765318Y-213503*
X683652Y-113228D02*
G03X683652Y-105354J3937D01*
Y-7874D02*
G03X683652Y0J3937D01*
Y363425D02*
G03X683652Y371299J3937D01*
X708848Y-113228D02*
G01X722440D01*
X708848Y-105354D02*
G03X708848Y-113228I1J-3937D01*
Y0D02*
G03X708848Y-7874I1J-3937D01*
Y371299D02*
G01X722440D01*
X708848D02*
G03X708848Y363425I1J-3937D01*
X830008Y-224003D02*
G01Y-206503D01*
X834374*
X836121Y-207378*
X837431Y-208545*
X838523Y-210294*
X839396Y-212337*
X839614Y-215253*
X839396Y-218170*
X838523Y-220212*
X837431Y-221962*
X836121Y-223128*
X834374Y-224003*
X830008*
X849036Y-216128D02*
G01X856023D01*
X855368Y-214086*
X854276Y-212920*
X852748Y-212337*
X851219Y-212628*
X849909Y-213503*
X849036Y-215545*
X848599Y-217295*
Y-219045*
X849036Y-220795*
X850128Y-222545*
X851438Y-223711*
X852966Y-224003*
X854494Y-223420*
X856023Y-221670*
X866536Y-221962D02*
G01X867628Y-223128D01*
X869156Y-224003*
X870466*
X871776Y-223420*
X872649Y-222545*
X873086Y-221379*
X872868Y-219628*
X871994Y-218753*
X868064Y-217003*
X867191Y-214961*
X867628Y-213503*
X868501Y-212628*
X869811Y-212337*
X871121Y-212628*
X872431Y-213503*
X887311Y-212337D02*
G01Y-224003D01*
Y-207670D02*
G01X886874Y-207378D01*
Y-206795*
X887311Y-206503*
X887748Y-206795*
Y-207378*
X887311Y-207670*
X901754Y-228378D02*
G01X903283Y-229545D01*
X905029Y-229836*
X906557Y-229545*
X907868Y-228087*
X908741Y-226045*
Y-212337*
Y-214670D02*
G01X907868Y-213503D01*
X906557Y-212628*
X905029Y-212337*
X903283Y-212920*
X902191Y-214086*
X901317Y-216128*
X900881Y-218170*
X901099Y-219920*
X901973Y-221962*
X903283Y-223420*
X905029Y-224003*
X906339Y-223711*
X907868Y-222545*
X908741Y-221379*
X918599Y-224003D02*
G01Y-212337D01*
Y-215253D02*
G01X919473Y-213795D01*
X920783Y-212628*
X922529Y-212337*
X924057Y-212628*
X925368Y-213795*
X926023Y-215836*
Y-224003*
X936536Y-216128D02*
G01X943523D01*
X942868Y-214086*
X941776Y-212920*
X940248Y-212337*
X938719Y-212628*
X937409Y-213503*
X936536Y-215545*
X936099Y-217295*
Y-219045*
X936536Y-220795*
X937628Y-222545*
X938938Y-223711*
X940466Y-224003*
X941994Y-223420*
X943523Y-221670*
X954254Y-224003D02*
G01Y-212337D01*
Y-214670D02*
G01X955346Y-213503D01*
X956438Y-212628*
X957966Y-212337*
X959057Y-212628*
X960368Y-213503*
X874194Y-265503D02*
G01X875286Y-267253D01*
X876596Y-268420*
X878124Y-269003*
X879871Y-268420*
X881181Y-267253*
X882491Y-265503*
X882928Y-263170*
Y-251503*
X896061Y-269003D02*
G01X894314Y-268711D01*
X892786Y-267545*
X891476Y-265795*
X890602Y-263753*
X890166Y-261420*
Y-259086*
X890602Y-256753*
X891476Y-254711*
X892786Y-252962*
X894314Y-251795*
X896061Y-251503*
X897807Y-251795*
X899336Y-252962*
X900646Y-254711*
X901520Y-256753*
X901956Y-259086*
Y-261420*
X901520Y-263753*
X900646Y-265795*
X899336Y-267545*
X897807Y-268711*
X896061Y-269003*
X913561D02*
G01Y-261128D01*
X909194Y-251503*
X917928D02*
G01X913561Y-261128D01*
X1001011Y-269003D02*
G01Y-251503D01*
X998391Y-255003*
Y-269003D02*
G01X1003631D01*
X1014363Y-254420D02*
G01X1015673Y-252670D01*
X1017201Y-251795*
X1018948Y-251503*
X1021131Y-252086*
X1022659Y-253545*
X1023096Y-255294*
X1022878Y-257045*
X1022004Y-258503*
X1017638Y-261420*
X1015673Y-263461*
X1014363Y-266379*
X1013926Y-269003*
X1023096*
X1032081Y-269586D02*
G01X1039941Y-251503D01*
X1048708Y-265503D02*
G01X1050017Y-267545D01*
X1051764Y-268711*
X1053729Y-269003*
X1055476Y-268711*
X1057223Y-267253*
X1058314Y-265503*
X1058533Y-263753*
X1058096Y-261712*
X1056568Y-260253*
X1055039Y-259670*
X1053074*
X1055039D02*
G01X1056349Y-258795D01*
X1057441Y-257337*
X1057878Y-255587*
X1057441Y-253836*
X1056349Y-252378*
X1054384Y-251503*
X1052419Y-251795*
X1050454Y-252962*
X1071011Y-251503D02*
G01X1069264Y-252086D01*
X1067954Y-253545*
X1067081Y-255294*
X1066426Y-257628*
X1066208Y-260253*
X1066426Y-262878*
X1067081Y-265212*
X1067954Y-266962*
X1069264Y-268420*
X1071011Y-269003*
X1072757Y-268420*
X1074068Y-266962*
X1074941Y-265212*
X1075596Y-262878*
X1075814Y-260253*
X1075596Y-257628*
X1074941Y-255294*
X1074068Y-253545*
X1072757Y-252086*
X1071011Y-251503*
X1084581Y-269586D02*
G01X1092441Y-251503D01*
X1101863Y-254420D02*
G01X1103173Y-252670D01*
X1104701Y-251795*
X1106448Y-251503*
X1108631Y-252086*
X1110159Y-253545*
X1110596Y-255294*
X1110378Y-257045*
X1109504Y-258503*
X1105138Y-261420*
X1103173Y-263461*
X1101863Y-266379*
X1101426Y-269003*
X1110596*
X1123511Y-251503D02*
G01X1121764Y-252086D01*
X1120454Y-253545*
X1119581Y-255294*
X1118926Y-257628*
X1118708Y-260253*
X1118926Y-262878*
X1119581Y-265212*
X1120454Y-266962*
X1121764Y-268420*
X1123511Y-269003*
X1125257Y-268420*
X1126568Y-266962*
X1127441Y-265212*
X1128096Y-262878*
X1128314Y-260253*
X1128096Y-257628*
X1127441Y-255294*
X1126568Y-253545*
X1125257Y-252086*
X1123511Y-251503*
X1141011Y-269003D02*
G01Y-251503D01*
X1138391Y-255003*
Y-269003D02*
G01X1143631D01*
X1154363Y-261712D02*
G01X1155891Y-259670D01*
X1157201Y-258503*
X1158948Y-257920*
X1160476Y-258503*
X1161568Y-259670*
X1162441Y-261420*
X1162659Y-263461*
X1162441Y-265212*
X1161568Y-266962*
X1160257Y-268420*
X1158729Y-269003*
X1156983Y-268420*
X1155454Y-266670*
X1154581Y-264045*
X1154363Y-261128*
X1154799Y-257337*
X1155454Y-255294*
X1156546Y-253253*
X1158074Y-251795*
X1159603Y-251503*
X1161131Y-252086*
X1162223Y-253545*
X1048708Y-224003D02*
G01Y-206503D01*
X1053074*
X1054821Y-207378*
X1056131Y-208545*
X1057223Y-210294*
X1058096Y-212337*
X1058314Y-215253*
X1058096Y-218170*
X1057223Y-220212*
X1056131Y-221962*
X1054821Y-223128*
X1053074Y-224003*
X1048708*
X1074941D02*
G01Y-212337D01*
Y-214378D02*
G01X1074068Y-213212D01*
X1072757Y-212628*
X1071229Y-212337*
X1069701Y-212920*
X1068391Y-214086*
X1067517Y-215836*
X1067081Y-218170*
X1067517Y-220503*
X1068391Y-222253*
X1069701Y-223420*
X1071229Y-224003*
X1072757Y-223711*
X1074068Y-222837*
X1074941Y-221670*
X1088511Y-206503D02*
G01Y-224003D01*
X1085454Y-212337D02*
G01X1091568D01*
X1102736Y-216128D02*
G01X1109723D01*
X1109068Y-214086*
X1107976Y-212920*
X1106448Y-212337*
X1104919Y-212628*
X1103609Y-213503*
X1102736Y-215545*
X1102299Y-217295*
Y-219045*
X1102736Y-220795*
X1103828Y-222545*
X1105138Y-223711*
X1106666Y-224003*
X1108194Y-223420*
X1109723Y-221670*
X720472Y217598D02*
G01X712598D01*
X710629Y219567D02*
G03X712598Y217598I1969D01*
X710629Y219567D02*
G01Y274843D01*
X712598Y276811D02*
G03X710629Y274843J-1969D01*
X712598Y276811D02*
G01X720472D01*
Y276811D02*
G03X722440Y278780J1968D01*
Y278780D02*
G01Y355551D01*
Y355551D02*
G03X714566Y363425I-7874D01*
Y363425D02*
G01X380905D01*
Y363425D02*
G03X373031Y355551J-7874D01*
Y355551D02*
G01Y273819D01*
Y273819D02*
G03X380905Y265945I7874D01*
Y265945D02*
G01X581102D01*
X588976Y258071D02*
G03X581102Y265945I-7874D01*
X588976Y258071D02*
G01Y7874D01*
Y7874D02*
G03X596850Y0I7874D01*
Y0D02*
G01X720472D01*
Y0D02*
G03X722440Y1969J1968D01*
Y1969D02*
G01Y21398D01*
Y21398D02*
G03X720472Y23366I-1968D01*
Y23366D02*
G01X694094D01*
X692125Y25335D02*
G03X694094Y23366I1969D01*
X692125Y25335D02*
G01Y42067D01*
X694094Y44035D02*
G03X692125Y42067J-1969D01*
X694094Y44035D02*
G01X699212D01*
Y44035D02*
G03X701181Y46004J1969D01*
Y46004D02*
G01Y171319D01*
Y171319D02*
G03X699212Y173287I-1968D01*
Y173287D02*
G01X694094D01*
X692125Y175256D02*
G03X694094Y173287I1969D01*
X692125Y175256D02*
G01Y191988D01*
X694094Y193957D02*
G03X692125Y191988J-1969D01*
X694094Y193957D02*
G01X720472D01*
Y193957D02*
G03X722440Y195925J1968D01*
Y195925D02*
G01Y215630D01*
Y215630D02*
G03X720472Y217598I-1968D01*
X1968Y40473D02*
G01X9842D01*
X11811Y38504D02*
G03X9842Y40473I-1969D01*
X11811Y38504D02*
G01Y-16772D01*
X9842Y-18740D02*
G03X11811Y-16772J1969D01*
X9842Y-18740D02*
G01X1968D01*
Y-18740D02*
G03X0Y-20709J-1968D01*
Y-20709D02*
G01Y-97480D01*
Y-97480D02*
G03X7874Y-105354I7874D01*
Y-105354D02*
G01X341535D01*
Y-105354D02*
G03X349409Y-97480J7874D01*
Y-97480D02*
G01Y-15748D01*
Y-15748D02*
G03X341535Y-7874I-7874D01*
Y-7874D02*
G01X141338D01*
X133464Y0D02*
G03X141338Y-7874I7874D01*
X133464Y0D02*
G01Y250197D01*
Y250197D02*
G03X125590Y258071I-7874D01*
Y258071D02*
G01X1968D01*
Y258071D02*
G03X0Y256102J-1968D01*
Y256102D02*
G01Y236673D01*
Y236673D02*
G03X1968Y234705I1968D01*
Y234705D02*
G01X28346D01*
X30315Y232736D02*
G03X28346Y234705I-1969D01*
X30315Y232736D02*
G01Y216004D01*
X28346Y214036D02*
G03X30315Y216004J1969D01*
X28346Y214036D02*
G01X23228D01*
Y214036D02*
G03X21259Y212067J-1969D01*
Y212067D02*
G01Y86752D01*
Y86752D02*
G03X23228Y84784I1968D01*
Y84784D02*
G01X28346D01*
X30315Y82815D02*
G03X28346Y84784I-1969D01*
X30315Y82815D02*
G01Y66083D01*
X28346Y64114D02*
G03X30315Y66083J1969D01*
X28346Y64114D02*
G01X1968D01*
Y64114D02*
G03X0Y62146J-1968D01*
Y62146D02*
G01Y42441D01*
Y42441D02*
G03X1968Y40473I1968D01*
X374999D02*
G01X382873D01*
X384842Y38504D02*
G03X382873Y40473I-1969D01*
X384842Y38504D02*
G01Y-16772D01*
X382873Y-18740D02*
G03X384842Y-16772J1969D01*
X382873Y-18740D02*
G01X374999D01*
Y-18740D02*
G03X373031Y-20709J-1968D01*
Y-20709D02*
G01Y-97480D01*
Y-97480D02*
G03X380905Y-105354I7874D01*
Y-105354D02*
G01X714566D01*
Y-105354D02*
G03X722440Y-97480J7874D01*
Y-97480D02*
G01Y-15748D01*
Y-15748D02*
G03X714566Y-7874I-7874D01*
Y-7874D02*
G01X514369D01*
X506495Y0D02*
G03X514369Y-7874I7874D01*
X506495Y0D02*
G01Y250197D01*
Y250197D02*
G03X498621Y258071I-7874D01*
Y258071D02*
G01X374999D01*
Y258071D02*
G03X373031Y256102J-1968D01*
Y256102D02*
G01Y236673D01*
Y236673D02*
G03X374999Y234705I1968D01*
Y234705D02*
G01X401377D01*
X403346Y232736D02*
G03X401377Y234705I-1969D01*
X403346Y232736D02*
G01Y216004D01*
X401377Y214036D02*
G03X403346Y216004J1969D01*
X401377Y214036D02*
G01X396259D01*
Y214036D02*
G03X394290Y212067J-1969D01*
Y212067D02*
G01Y86752D01*
Y86752D02*
G03X396259Y84784I1968D01*
Y84784D02*
G01X401377D01*
X403346Y82815D02*
G03X401377Y84784I-1969D01*
X403346Y82815D02*
G01Y66083D01*
X401377Y64114D02*
G03X403346Y66083J1969D01*
X401377Y64114D02*
G01X374999D01*
Y64114D02*
G03X373031Y62146J-1968D01*
Y62146D02*
G01Y42441D01*
Y42441D02*
G03X374999Y40473I1968D01*
M02*
